FILE_TYPE = MACRO_DRAWING;
SET COLOR_WIRE YELLOW;
SET COLOR_PROP ORANGE;
SET COLOR_DOT WHITE;
SET COLOR_ARC YELLOW;
SET COLOR_BODY GREEN;
SET COLOR_NOTE PURPLE;
SET PROP_DISPLAY VALUE;
SET PAGE_NUMBER P40;
FORCEADD GENOA_SP5..4
(-4600 3650);
FORCEPROP 1 LAST LOCATION U26
J 0
(-5245 6481);
DISPLAY 0.489362 (-5245 6481);
PAINT SKYBLUE (-5245 6481);
FORCEPROP 0 LAST $SEC 4
J 0
(-5225 6525);
DISPLAY 0.680851 (-5225 6525);
PAINT MONO (-5225 6525);
DISPLAY INVISIBLE (-5225 6525);
FORCEPROP 0 LAST CDS_SEC 4
J 0
(-5250 6475);
DISPLAY 1.021277 (-5250 6475);
DISPLAY INVISIBLE (-5250 6475);
FORCEPROP 0 LASTPIN (-5400 3025) $PN BC60
J 2
(-5410 3035);
DISPLAY 0.489362 (-5410 3035);
PAINT MONO (-5410 3035);
FORCEPROP 0 LASTPIN (-5400 2975) $PN BD60
J 2
(-5410 2985);
DISPLAY 0.489362 (-5410 2985);
PAINT MONO (-5410 2985);
FORCEPROP 0 LASTPIN (-5400 1875) $PN BF60
J 2
(-5410 1885);
DISPLAY 0.489362 (-5410 1885);
PAINT MONO (-5410 1885);
FORCEPROP 0 LASTPIN (-5400 1825) $PN BG60
J 2
(-5410 1835);
DISPLAY 0.489362 (-5410 1835);
PAINT MONO (-5410 1835);
FORCEPROP 0 LASTPIN (-5400 2175) $PN AT58
J 2
(-5410 2185);
DISPLAY 0.489362 (-5410 2185);
PAINT MONO (-5410 2185);
FORCEPROP 0 LASTPIN (-5400 2075) $PN AU59
J 2
(-5410 2085);
DISPLAY 0.489362 (-5410 2085);
PAINT MONO (-5410 2085);
FORCEPROP 0 LASTPIN (-5400 2875) $PN AV60
J 2
(-5410 2885);
DISPLAY 0.489362 (-5410 2885);
PAINT MONO (-5410 2885);
FORCEPROP 0 LASTPIN (-5400 2825) $PN AW59
J 2
(-5410 2835);
DISPLAY 0.489362 (-5410 2835);
PAINT MONO (-5410 2835);
FORCEPROP 0 LASTPIN (-5400 2725) $PN BN59
J 2
(-5410 2735);
DISPLAY 0.489362 (-5410 2735);
PAINT MONO (-5410 2735);
FORCEPROP 0 LASTPIN (-5400 1725) $PN AU60
J 2
(-5410 1735);
DISPLAY 0.489362 (-5410 1735);
PAINT MONO (-5410 1735);
FORCEPROP 0 LASTPIN (-5400 1675) $PN AV58
J 2
(-5410 1685);
DISPLAY 0.489362 (-5410 1685);
PAINT MONO (-5410 1685);
FORCEPROP 0 LASTPIN (-5400 1575) $PN BP58
J 2
(-5410 1585);
DISPLAY 0.489362 (-5410 1585);
PAINT MONO (-5410 1585);
FORCEPROP 0 LASTPIN (-5400 3875) $PN AW60
J 2
(-5410 3885);
DISPLAY 0.489362 (-5410 3885);
PAINT MONO (-5410 3885);
FORCEPROP 0 LASTPIN (-5400 3825) $PN AY60
J 2
(-5410 3835);
DISPLAY 0.489362 (-5410 3835);
PAINT MONO (-5410 3835);
FORCEPROP 0 LASTPIN (-5400 3775) $PN AY58
J 2
(-5410 3785);
DISPLAY 0.489362 (-5410 3785);
PAINT MONO (-5410 3785);
FORCEPROP 0 LASTPIN (-5400 3725) $PN BA59
J 2
(-5410 3735);
DISPLAY 0.489362 (-5410 3735);
PAINT MONO (-5410 3735);
FORCEPROP 0 LASTPIN (-5400 3675) $PN BA60
J 2
(-5410 3685);
DISPLAY 0.489362 (-5410 3685);
PAINT MONO (-5410 3685);
FORCEPROP 0 LASTPIN (-5400 3625) $PN BB60
J 2
(-5410 3635);
DISPLAY 0.489362 (-5410 3635);
PAINT MONO (-5410 3635);
FORCEPROP 0 LASTPIN (-5400 3575) $PN BB58
J 2
(-5410 3585);
DISPLAY 0.489362 (-5410 3585);
PAINT MONO (-5410 3585);
FORCEPROP 0 LASTPIN (-3800 2425) $PN AJ60
J 0
(-3790 2435);
DISPLAY 0.489362 (-3790 2435);
PAINT MONO (-3790 2435);
FORCEPROP 0 LASTPIN (-3800 2375) $PN AK58
J 0
(-3790 2385);
DISPLAY 0.489362 (-3790 2385);
PAINT MONO (-3790 2385);
FORCEPROP 0 LASTPIN (-3800 2325) $PN AK60
J 0
(-3790 2335);
DISPLAY 0.489362 (-3790 2335);
PAINT MONO (-3790 2335);
FORCEPROP 0 LASTPIN (-3800 2275) $PN AL59
J 0
(-3790 2285);
DISPLAY 0.489362 (-3790 2285);
PAINT MONO (-3790 2285);
FORCEPROP 0 LASTPIN (-3800 2225) $PN AN60
J 0
(-3790 2235);
DISPLAY 0.489362 (-3790 2235);
PAINT MONO (-3790 2235);
FORCEPROP 0 LASTPIN (-3800 2175) $PN AP58
J 0
(-3790 2185);
DISPLAY 0.489362 (-3790 2185);
PAINT MONO (-3790 2185);
FORCEPROP 0 LASTPIN (-3800 2125) $PN AP60
J 0
(-3790 2135);
DISPLAY 0.489362 (-3790 2135);
PAINT MONO (-3790 2135);
FORCEPROP 0 LASTPIN (-3800 2075) $PN AR59
J 0
(-3790 2085);
DISPLAY 0.489362 (-3790 2085);
PAINT MONO (-3790 2085);
FORCEPROP 0 LASTPIN (-3800 6025) $PN E60
J 0
(-3790 6035);
DISPLAY 0.489362 (-3790 6035);
PAINT MONO (-3790 6035);
FORCEPROP 0 LASTPIN (-3800 5975) $PN F58
J 0
(-3790 5985);
DISPLAY 0.489362 (-3790 5985);
PAINT MONO (-3790 5985);
FORCEPROP 0 LASTPIN (-3800 5925) $PN F60
J 0
(-3790 5935);
DISPLAY 0.489362 (-3790 5935);
PAINT MONO (-3790 5935);
FORCEPROP 0 LASTPIN (-3800 5875) $PN G59
J 0
(-3790 5885);
DISPLAY 0.489362 (-3790 5885);
PAINT MONO (-3790 5885);
FORCEPROP 0 LASTPIN (-3800 5825) $PN J60
J 0
(-3790 5835);
DISPLAY 0.489362 (-3790 5835);
PAINT MONO (-3790 5835);
FORCEPROP 0 LASTPIN (-3800 5775) $PN K58
J 0
(-3790 5785);
DISPLAY 0.489362 (-3790 5785);
PAINT MONO (-3790 5785);
FORCEPROP 0 LASTPIN (-3800 5725) $PN K60
J 0
(-3790 5735);
DISPLAY 0.489362 (-3790 5735);
PAINT MONO (-3790 5735);
FORCEPROP 0 LASTPIN (-3800 5675) $PN L59
J 0
(-3790 5685);
DISPLAY 0.489362 (-3790 5685);
PAINT MONO (-3790 5685);
FORCEPROP 0 LASTPIN (-3800 5575) $PN L60
J 0
(-3790 5585);
DISPLAY 0.489362 (-3790 5585);
PAINT MONO (-3790 5585);
FORCEPROP 0 LASTPIN (-3800 5525) $PN M58
J 0
(-3790 5535);
DISPLAY 0.489362 (-3790 5535);
PAINT MONO (-3790 5535);
FORCEPROP 0 LASTPIN (-3800 5475) $PN M60
J 0
(-3790 5485);
DISPLAY 0.489362 (-3790 5485);
PAINT MONO (-3790 5485);
FORCEPROP 0 LASTPIN (-3800 5425) $PN N59
J 0
(-3790 5435);
DISPLAY 0.489362 (-3790 5435);
PAINT MONO (-3790 5435);
FORCEPROP 0 LASTPIN (-3800 5375) $PN R60
J 0
(-3790 5385);
DISPLAY 0.489362 (-3790 5385);
PAINT MONO (-3790 5385);
FORCEPROP 0 LASTPIN (-3800 5325) $PN T58
J 0
(-3790 5335);
DISPLAY 0.489362 (-3790 5335);
PAINT MONO (-3790 5335);
FORCEPROP 0 LASTPIN (-3800 5275) $PN T60
J 0
(-3790 5285);
DISPLAY 0.489362 (-3790 5285);
PAINT MONO (-3790 5285);
FORCEPROP 0 LASTPIN (-3800 5225) $PN U59
J 0
(-3790 5235);
DISPLAY 0.489362 (-3790 5235);
PAINT MONO (-3790 5235);
FORCEPROP 0 LASTPIN (-3800 5125) $PN U60
J 0
(-3790 5135);
DISPLAY 0.489362 (-3790 5135);
PAINT MONO (-3790 5135);
FORCEPROP 0 LASTPIN (-3800 5075) $PN V58
J 0
(-3790 5085);
DISPLAY 0.489362 (-3790 5085);
PAINT MONO (-3790 5085);
FORCEPROP 0 LASTPIN (-3800 5025) $PN V60
J 0
(-3790 5035);
DISPLAY 0.489362 (-3790 5035);
PAINT MONO (-3790 5035);
FORCEPROP 0 LASTPIN (-3800 4975) $PN W59
J 0
(-3790 4985);
DISPLAY 0.489362 (-3790 4985);
PAINT MONO (-3790 4985);
FORCEPROP 0 LASTPIN (-3800 4925) $PN AA60
J 0
(-3790 4935);
DISPLAY 0.489362 (-3790 4935);
PAINT MONO (-3790 4935);
FORCEPROP 0 LASTPIN (-3800 4875) $PN AB58
J 0
(-3790 4885);
DISPLAY 0.489362 (-3790 4885);
PAINT MONO (-3790 4885);
FORCEPROP 0 LASTPIN (-3800 4825) $PN AB60
J 0
(-3790 4835);
DISPLAY 0.489362 (-3790 4835);
PAINT MONO (-3790 4835);
FORCEPROP 0 LASTPIN (-3800 4775) $PN AC59
J 0
(-3790 4785);
DISPLAY 0.489362 (-3790 4785);
PAINT MONO (-3790 4785);
FORCEPROP 0 LASTPIN (-3800 4675) $PN AC60
J 0
(-3790 4685);
DISPLAY 0.489362 (-3790 4685);
PAINT MONO (-3790 4685);
FORCEPROP 0 LASTPIN (-3800 4625) $PN AD58
J 0
(-3790 4635);
DISPLAY 0.489362 (-3790 4635);
PAINT MONO (-3790 4635);
FORCEPROP 0 LASTPIN (-3800 4575) $PN AD60
J 0
(-3790 4585);
DISPLAY 0.489362 (-3790 4585);
PAINT MONO (-3790 4585);
FORCEPROP 0 LASTPIN (-3800 4525) $PN AE59
J 0
(-3790 4535);
DISPLAY 0.489362 (-3790 4535);
PAINT MONO (-3790 4535);
FORCEPROP 0 LASTPIN (-3800 4475) $PN AG60
J 0
(-3790 4485);
DISPLAY 0.489362 (-3790 4485);
PAINT MONO (-3790 4485);
FORCEPROP 0 LASTPIN (-3800 4425) $PN AH58
J 0
(-3790 4435);
DISPLAY 0.489362 (-3790 4435);
PAINT MONO (-3790 4435);
FORCEPROP 0 LASTPIN (-3800 4375) $PN AH60
J 0
(-3790 4385);
DISPLAY 0.489362 (-3790 4385);
PAINT MONO (-3790 4385);
FORCEPROP 0 LASTPIN (-3800 4325) $PN AJ59
J 0
(-3790 4335);
DISPLAY 0.489362 (-3790 4335);
PAINT MONO (-3790 4335);
FORCEPROP 0 LASTPIN (-5400 6025) $PN G60
J 2
(-5410 6035);
DISPLAY 0.489362 (-5410 6035);
PAINT MONO (-5410 6035);
FORCEPROP 0 LASTPIN (-5400 5925) $PN N60
J 2
(-5410 5935);
DISPLAY 0.489362 (-5410 5935);
PAINT MONO (-5410 5935);
FORCEPROP 0 LASTPIN (-5400 5825) $PN W60
J 2
(-5410 5835);
DISPLAY 0.489362 (-5410 5835);
PAINT MONO (-5410 5835);
FORCEPROP 0 LASTPIN (-5400 5725) $PN AE60
J 2
(-5410 5735);
DISPLAY 0.489362 (-5410 5735);
PAINT MONO (-5410 5735);
FORCEPROP 0 LASTPIN (-5400 5625) $PN AL60
J 2
(-5410 5635);
DISPLAY 0.489362 (-5410 5635);
PAINT MONO (-5410 5635);
FORCEPROP 0 LASTPIN (-5400 5525) $PN J59
J 2
(-5410 5535);
DISPLAY 0.489362 (-5410 5535);
PAINT MONO (-5410 5535);
FORCEPROP 0 LASTPIN (-5400 5425) $PN R59
J 2
(-5410 5435);
DISPLAY 0.489362 (-5410 5435);
PAINT MONO (-5410 5435);
FORCEPROP 0 LASTPIN (-5400 5325) $PN AA59
J 2
(-5410 5335);
DISPLAY 0.489362 (-5410 5335);
PAINT MONO (-5410 5335);
FORCEPROP 0 LASTPIN (-5400 5225) $PN AG59
J 2
(-5410 5235);
DISPLAY 0.489362 (-5410 5235);
PAINT MONO (-5410 5235);
FORCEPROP 0 LASTPIN (-5400 5125) $PN AN59
J 2
(-5410 5135);
DISPLAY 0.489362 (-5410 5135);
PAINT MONO (-5410 5135);
FORCEPROP 0 LASTPIN (-5400 5975) $PN H60
J 2
(-5410 5985);
DISPLAY 0.489362 (-5410 5985);
PAINT MONO (-5410 5985);
FORCEPROP 0 LASTPIN (-5400 5875) $PN P60
J 2
(-5410 5885);
DISPLAY 0.489362 (-5410 5885);
PAINT MONO (-5410 5885);
FORCEPROP 0 LASTPIN (-5400 5775) $PN Y60
J 2
(-5410 5785);
DISPLAY 0.489362 (-5410 5785);
PAINT MONO (-5410 5785);
FORCEPROP 0 LASTPIN (-5400 5675) $PN AF60
J 2
(-5410 5685);
DISPLAY 0.489362 (-5410 5685);
PAINT MONO (-5410 5685);
FORCEPROP 0 LASTPIN (-5400 5575) $PN AM60
J 2
(-5410 5585);
DISPLAY 0.489362 (-5410 5585);
PAINT MONO (-5410 5585);
FORCEPROP 0 LASTPIN (-5400 5475) $PN H58
J 2
(-5410 5485);
DISPLAY 0.489362 (-5410 5485);
PAINT MONO (-5410 5485);
FORCEPROP 0 LASTPIN (-5400 5375) $PN P58
J 2
(-5410 5385);
DISPLAY 0.489362 (-5410 5385);
PAINT MONO (-5410 5385);
FORCEPROP 0 LASTPIN (-5400 5275) $PN Y58
J 2
(-5410 5285);
DISPLAY 0.489362 (-5410 5285);
PAINT MONO (-5410 5285);
FORCEPROP 0 LASTPIN (-5400 5175) $PN AF58
J 2
(-5410 5185);
DISPLAY 0.489362 (-5410 5185);
PAINT MONO (-5410 5185);
FORCEPROP 0 LASTPIN (-5400 5075) $PN AM58
J 2
(-5410 5085);
DISPLAY 0.489362 (-5410 5085);
PAINT MONO (-5410 5085);
FORCEPROP 0 LASTPIN (-5400 2625) $PN BC59
J 2
(-5410 2635);
DISPLAY 0.489362 (-5410 2635);
PAINT MONO (-5410 2635);
FORCEPROP 0 LASTPIN (-5400 2525) $PN BM58
J 2
(-5410 2535);
DISPLAY 0.489362 (-5410 2535);
PAINT MONO (-5410 2535);
FORCEPROP 0 LASTPIN (-5400 2475) $PN BN60
J 2
(-5410 2485);
DISPLAY 0.489362 (-5410 2485);
PAINT MONO (-5410 2485);
FORCEPROP 0 LASTPIN (-5400 2375) $PN BP60
J 2
(-5410 2385);
DISPLAY 0.489362 (-5410 2385);
PAINT MONO (-5410 2385);
FORCEPROP 0 LASTPIN (-5400 1475) $PN BL59
J 2
(-5410 1485);
DISPLAY 0.489362 (-5410 1485);
PAINT MONO (-5410 1485);
FORCEPROP 0 LASTPIN (-5400 1425) $PN BM60
J 2
(-5410 1435);
DISPLAY 0.489362 (-5410 1435);
PAINT MONO (-5410 1435);
FORCEPROP 0 LASTPIN (-5400 1325) $PN BR60
J 2
(-5410 1335);
DISPLAY 0.489362 (-5410 1335);
PAINT MONO (-5410 1335);
FORCEPROP 0 LASTPIN (-5400 3475) $PN BG59
J 2
(-5410 3485);
DISPLAY 0.489362 (-5410 3485);
PAINT MONO (-5410 3485);
FORCEPROP 0 LASTPIN (-5400 3425) $PN BH58
J 2
(-5410 3435);
DISPLAY 0.489362 (-5410 3435);
PAINT MONO (-5410 3435);
FORCEPROP 0 LASTPIN (-5400 3375) $PN BH60
J 2
(-5410 3385);
DISPLAY 0.489362 (-5410 3385);
PAINT MONO (-5410 3385);
FORCEPROP 0 LASTPIN (-5400 3325) $PN BJ60
J 2
(-5410 3335);
DISPLAY 0.489362 (-5410 3335);
PAINT MONO (-5410 3335);
FORCEPROP 0 LASTPIN (-5400 3275) $PN BJ59
J 2
(-5410 3285);
DISPLAY 0.489362 (-5410 3285);
PAINT MONO (-5410 3285);
FORCEPROP 0 LASTPIN (-5400 3225) $PN BK58
J 2
(-5410 3235);
DISPLAY 0.489362 (-5410 3235);
PAINT MONO (-5410 3235);
FORCEPROP 0 LASTPIN (-5400 3175) $PN BK60
J 2
(-5410 3185);
DISPLAY 0.489362 (-5410 3185);
PAINT MONO (-5410 3185);
FORCEPROP 0 LASTPIN (-3800 1975) $PN BY60
J 0
(-3790 1985);
DISPLAY 0.489362 (-3790 1985);
PAINT MONO (-3790 1985);
FORCEPROP 0 LASTPIN (-3800 1925) $PN CA59
J 0
(-3790 1935);
DISPLAY 0.489362 (-3790 1935);
PAINT MONO (-3790 1935);
FORCEPROP 0 LASTPIN (-3800 1875) $PN CA60
J 0
(-3790 1885);
DISPLAY 0.489362 (-3790 1885);
PAINT MONO (-3790 1885);
FORCEPROP 0 LASTPIN (-3800 1825) $PN CB58
J 0
(-3790 1835);
DISPLAY 0.489362 (-3790 1835);
PAINT MONO (-3790 1835);
FORCEPROP 0 LASTPIN (-3800 1775) $PN BT60
J 0
(-3790 1785);
DISPLAY 0.489362 (-3790 1785);
PAINT MONO (-3790 1785);
FORCEPROP 0 LASTPIN (-3800 1725) $PN BU59
J 0
(-3790 1735);
DISPLAY 0.489362 (-3790 1735);
PAINT MONO (-3790 1735);
FORCEPROP 0 LASTPIN (-3800 1675) $PN BU60
J 0
(-3790 1685);
DISPLAY 0.489362 (-3790 1685);
PAINT MONO (-3790 1685);
FORCEPROP 0 LASTPIN (-3800 1625) $PN BV58
J 0
(-3790 1635);
DISPLAY 0.489362 (-3790 1635);
PAINT MONO (-3790 1635);
FORCEPROP 0 LASTPIN (-3800 4225) $PN CB60
J 0
(-3790 4235);
DISPLAY 0.489362 (-3790 4235);
PAINT MONO (-3790 4235);
FORCEPROP 0 LASTPIN (-3800 4175) $PN CC59
J 0
(-3790 4185);
DISPLAY 0.489362 (-3790 4185);
PAINT MONO (-3790 4185);
FORCEPROP 0 LASTPIN (-3800 4125) $PN CC60
J 0
(-3790 4135);
DISPLAY 0.489362 (-3790 4135);
PAINT MONO (-3790 4135);
FORCEPROP 0 LASTPIN (-3800 4075) $PN CD58
J 0
(-3790 4085);
DISPLAY 0.489362 (-3790 4085);
PAINT MONO (-3790 4085);
FORCEPROP 0 LASTPIN (-3800 4025) $PN CF60
J 0
(-3790 4035);
DISPLAY 0.489362 (-3790 4035);
PAINT MONO (-3790 4035);
FORCEPROP 0 LASTPIN (-3800 3975) $PN CG59
J 0
(-3790 3985);
DISPLAY 0.489362 (-3790 3985);
PAINT MONO (-3790 3985);
FORCEPROP 0 LASTPIN (-3800 3925) $PN CG60
J 0
(-3790 3935);
DISPLAY 0.489362 (-3790 3935);
PAINT MONO (-3790 3935);
FORCEPROP 0 LASTPIN (-3800 3875) $PN CH58
J 0
(-3790 3885);
DISPLAY 0.489362 (-3790 3885);
PAINT MONO (-3790 3885);
FORCEPROP 0 LASTPIN (-3800 3775) $PN CH60
J 0
(-3790 3785);
DISPLAY 0.489362 (-3790 3785);
PAINT MONO (-3790 3785);
FORCEPROP 0 LASTPIN (-3800 3725) $PN CJ59
J 0
(-3790 3735);
DISPLAY 0.489362 (-3790 3735);
PAINT MONO (-3790 3735);
FORCEPROP 0 LASTPIN (-3800 3675) $PN CJ60
J 0
(-3790 3685);
DISPLAY 0.489362 (-3790 3685);
PAINT MONO (-3790 3685);
FORCEPROP 0 LASTPIN (-3800 3625) $PN CK58
J 0
(-3790 3635);
DISPLAY 0.489362 (-3790 3635);
PAINT MONO (-3790 3635);
FORCEPROP 0 LASTPIN (-3800 3575) $PN CM60
J 0
(-3790 3585);
DISPLAY 0.489362 (-3790 3585);
PAINT MONO (-3790 3585);
FORCEPROP 0 LASTPIN (-3800 3525) $PN CN59
J 0
(-3790 3535);
DISPLAY 0.489362 (-3790 3535);
PAINT MONO (-3790 3535);
FORCEPROP 0 LASTPIN (-3800 3475) $PN CN60
J 0
(-3790 3485);
DISPLAY 0.489362 (-3790 3485);
PAINT MONO (-3790 3485);
FORCEPROP 0 LASTPIN (-3800 3425) $PN CP58
J 0
(-3790 3435);
DISPLAY 0.489362 (-3790 3435);
PAINT MONO (-3790 3435);
FORCEPROP 0 LASTPIN (-3800 3325) $PN CP60
J 0
(-3790 3335);
DISPLAY 0.489362 (-3790 3335);
PAINT MONO (-3790 3335);
FORCEPROP 0 LASTPIN (-3800 3275) $PN CR59
J 0
(-3790 3285);
DISPLAY 0.489362 (-3790 3285);
PAINT MONO (-3790 3285);
FORCEPROP 0 LASTPIN (-3800 3225) $PN CR60
J 0
(-3790 3235);
DISPLAY 0.489362 (-3790 3235);
PAINT MONO (-3790 3235);
FORCEPROP 0 LASTPIN (-3800 3175) $PN CT58
J 0
(-3790 3185);
DISPLAY 0.489362 (-3790 3185);
PAINT MONO (-3790 3185);
FORCEPROP 0 LASTPIN (-3800 3125) $PN CV60
J 0
(-3790 3135);
DISPLAY 0.489362 (-3790 3135);
PAINT MONO (-3790 3135);
FORCEPROP 0 LASTPIN (-3800 3075) $PN CW59
J 0
(-3790 3085);
DISPLAY 0.489362 (-3790 3085);
PAINT MONO (-3790 3085);
FORCEPROP 0 LASTPIN (-3800 3025) $PN CW60
J 0
(-3790 3035);
DISPLAY 0.489362 (-3790 3035);
PAINT MONO (-3790 3035);
FORCEPROP 0 LASTPIN (-3800 2975) $PN CY58
J 0
(-3790 2985);
DISPLAY 0.489362 (-3790 2985);
PAINT MONO (-3790 2985);
FORCEPROP 0 LASTPIN (-3800 2875) $PN CY60
J 0
(-3790 2885);
DISPLAY 0.489362 (-3790 2885);
PAINT MONO (-3790 2885);
FORCEPROP 0 LASTPIN (-3800 2825) $PN DA59
J 0
(-3790 2835);
DISPLAY 0.489362 (-3790 2835);
PAINT MONO (-3790 2835);
FORCEPROP 0 LASTPIN (-3800 2775) $PN DA60
J 0
(-3790 2785);
DISPLAY 0.489362 (-3790 2785);
PAINT MONO (-3790 2785);
FORCEPROP 0 LASTPIN (-3800 2725) $PN DB58
J 0
(-3790 2735);
DISPLAY 0.489362 (-3790 2735);
PAINT MONO (-3790 2735);
FORCEPROP 0 LASTPIN (-3800 2675) $PN DD60
J 0
(-3790 2685);
DISPLAY 0.489362 (-3790 2685);
PAINT MONO (-3790 2685);
FORCEPROP 0 LASTPIN (-3800 2625) $PN DE59
J 0
(-3790 2635);
DISPLAY 0.489362 (-3790 2635);
PAINT MONO (-3790 2635);
FORCEPROP 0 LASTPIN (-3800 2575) $PN DE60
J 0
(-3790 2585);
DISPLAY 0.489362 (-3790 2585);
PAINT MONO (-3790 2585);
FORCEPROP 0 LASTPIN (-3800 2525) $PN DF60
J 0
(-3790 2535);
DISPLAY 0.489362 (-3790 2535);
PAINT MONO (-3790 2535);
FORCEPROP 0 LASTPIN (-5400 4975) $PN CD60
J 2
(-5410 4985);
DISPLAY 0.489362 (-5410 4985);
PAINT MONO (-5410 4985);
FORCEPROP 0 LASTPIN (-5400 4875) $PN CK60
J 2
(-5410 4885);
DISPLAY 0.489362 (-5410 4885);
PAINT MONO (-5410 4885);
FORCEPROP 0 LASTPIN (-5400 4775) $PN CT60
J 2
(-5410 4785);
DISPLAY 0.489362 (-5410 4785);
PAINT MONO (-5410 4785);
FORCEPROP 0 LASTPIN (-5400 4675) $PN DB60
J 2
(-5410 4685);
DISPLAY 0.489362 (-5410 4685);
PAINT MONO (-5410 4685);
FORCEPROP 0 LASTPIN (-5400 4575) $PN BY58
J 2
(-5410 4585);
DISPLAY 0.489362 (-5410 4585);
PAINT MONO (-5410 4585);
FORCEPROP 0 LASTPIN (-5400 4475) $PN CF58
J 2
(-5410 4485);
DISPLAY 0.489362 (-5410 4485);
PAINT MONO (-5410 4485);
FORCEPROP 0 LASTPIN (-5400 4375) $PN CM58
J 2
(-5410 4385);
DISPLAY 0.489362 (-5410 4385);
PAINT MONO (-5410 4385);
FORCEPROP 0 LASTPIN (-5400 4275) $PN CV58
J 2
(-5410 4285);
DISPLAY 0.489362 (-5410 4285);
PAINT MONO (-5410 4285);
FORCEPROP 0 LASTPIN (-5400 4175) $PN DD58
J 2
(-5410 4185);
DISPLAY 0.489362 (-5410 4185);
PAINT MONO (-5410 4185);
FORCEPROP 0 LASTPIN (-5400 4075) $PN BV60
J 2
(-5410 4085);
DISPLAY 0.489362 (-5410 4085);
PAINT MONO (-5410 4085);
FORCEPROP 0 LASTPIN (-5400 4925) $PN CE60
J 2
(-5410 4935);
DISPLAY 0.489362 (-5410 4935);
PAINT MONO (-5410 4935);
FORCEPROP 0 LASTPIN (-5400 4825) $PN CL60
J 2
(-5410 4835);
DISPLAY 0.489362 (-5410 4835);
PAINT MONO (-5410 4835);
FORCEPROP 0 LASTPIN (-5400 4725) $PN CU60
J 2
(-5410 4735);
DISPLAY 0.489362 (-5410 4735);
PAINT MONO (-5410 4735);
FORCEPROP 0 LASTPIN (-5400 4625) $PN DC60
J 2
(-5410 4635);
DISPLAY 0.489362 (-5410 4635);
PAINT MONO (-5410 4635);
FORCEPROP 0 LASTPIN (-5400 4525) $PN BW59
J 2
(-5410 4535);
DISPLAY 0.489362 (-5410 4535);
PAINT MONO (-5410 4535);
FORCEPROP 0 LASTPIN (-5400 4425) $PN CE59
J 2
(-5410 4435);
DISPLAY 0.489362 (-5410 4435);
PAINT MONO (-5410 4435);
FORCEPROP 0 LASTPIN (-5400 4325) $PN CL59
J 2
(-5410 4335);
DISPLAY 0.489362 (-5410 4335);
PAINT MONO (-5410 4335);
FORCEPROP 0 LASTPIN (-5400 4225) $PN CU59
J 2
(-5410 4235);
DISPLAY 0.489362 (-5410 4235);
PAINT MONO (-5410 4235);
FORCEPROP 0 LASTPIN (-5400 4125) $PN DC59
J 2
(-5410 4135);
DISPLAY 0.489362 (-5410 4135);
PAINT MONO (-5410 4135);
FORCEPROP 0 LASTPIN (-5400 4025) $PN BW60
J 2
(-5410 4035);
DISPLAY 0.489362 (-5410 4035);
PAINT MONO (-5410 4035);
FORCEPROP 0 LASTPIN (-5400 2275) $PN BL60
J 2
(-5410 2285);
DISPLAY 0.489362 (-5410 2285);
PAINT MONO (-5410 2285);
FORCEPROP 0 LASTPIN (-5400 1225) $PN BF58
J 2
(-5410 1235);
DISPLAY 0.489362 (-5410 1235);
PAINT MONO (-5410 1235);
FORCEPROP 2 LAST PART_TYPE SMLF
J 0
(-5250 6425);
DISPLAY 1.021277 (-5250 6425);
FORCEPROP 1 LAST MATERIAL IO
J 0
(-5245 6207);
DISPLAY 0.489362 (-5245 6207);
PAINT SKYBLUE (-5245 6207);
FORCEPROP 2 LAST VALUE SOCKET6096_13568-001
J 0
(-5250 6325);
DISPLAY 0.489362 (-5250 6325);
PAINT SKYBLUE (-5250 6325);
FORCEPROP 2 LAST CDS_LIB pure_quanta
J 0
(-4600 3650);
DISPLAY INVISIBLE (-4600 3650);
FORCEPROP 1 LAST CDS_LMAN_SYM_OUTLINE -650,2525,650,-2525
J 0
(-4600 3650);
DISPLAY 0.468085 (-4600 3650);
PAINT GREEN (-4600 3650);
DISPLAY INVISIBLE (-4600 3650);
FORCEPROP 1 LAST NEEDS_NO_SIZE TRUE
J 0
(-4600 3650);
DISPLAY 0.723404 (-4600 3650);
PAINT GREEN (-4600 3650);
DISPLAY INVISIBLE (-4600 3650);
FORCEPROP 1 LAST PATH I159
J 0
(-4600 3650);
DISPLAY 0.723404 (-4600 3650);
PAINT GREEN (-4600 3650);
DISPLAY INVISIBLE (-4600 3650);
FORCEPROP 1 LAST PART_NUMBER DGA^6000030
J 0
(-5245 6334);
DISPLAY 0.489362 (-5245 6334);
PAINT SKYBLUE (-5245 6334);
DISPLAY INVISIBLE (-5245 6334);
FORCEADD OFFPAGE..3
(-2600 6050);
FORCEPROP 2 LAST $XR0 101 
J 0
(-2386 6050);
DISPLAY 0.638298 (-2386 6050);
PAINT MONO (-2386 6050);
FORCEPROP 2 LAST CDS_LIB mstr_standard
J 0
(-2600 6050);
DISPLAY 0.723404 (-2600 6050);
PAINT MONO (-2600 6050);
DISPLAY INVISIBLE (-2600 6050);
FORCEPROP 1 LAST OFFPAGE TRUE
J 0
(-2275 5925);
DISPLAY 0.872340 (-2275 5925);
PAINT GREEN (-2275 5925);
DISPLAY INVISIBLE (-2275 5925);
FORCEPROP 1 LAST COMMENT_BODY TRUE
J 0
(-2650 5950);
DISPLAY 0.872340 (-2650 5950);
PAINT GREEN (-2650 5950);
DISPLAY INVISIBLE (-2650 5950);
FORCEPROP 2 LAST PATH I160
J 0
(-2375 6100);
DISPLAY 1.021277 (-2375 6100);
DISPLAY INVISIBLE (-2375 6100);
FORCEADD OFFPAGE..3
(-2600 4250);
FORCEPROP 2 LAST $XR0 101 
J 0
(-2386 4250);
DISPLAY 0.638298 (-2386 4250);
PAINT MONO (-2386 4250);
FORCEPROP 2 LAST CDS_LIB mstr_standard
J 0
(-2600 4250);
DISPLAY 0.723404 (-2600 4250);
PAINT MONO (-2600 4250);
DISPLAY INVISIBLE (-2600 4250);
FORCEPROP 1 LAST OFFPAGE TRUE
J 0
(-2275 4125);
DISPLAY 0.872340 (-2275 4125);
PAINT GREEN (-2275 4125);
DISPLAY INVISIBLE (-2275 4125);
FORCEPROP 1 LAST COMMENT_BODY TRUE
J 0
(-2650 4150);
DISPLAY 0.872340 (-2650 4150);
PAINT GREEN (-2650 4150);
DISPLAY INVISIBLE (-2650 4150);
FORCEPROP 2 LAST PATH I161
J 0
(-2375 4300);
DISPLAY 1.021277 (-2375 4300);
DISPLAY INVISIBLE (-2375 4300);
FORCEADD TAP..1
(-3325 5975);
FORCEPROP 3 LASTPIN (-3375 5975) SIG_NAME M_D_CPU1_SA_DQ<1>
J 0
(-3365 5985);
DISPLAY 0.659574 (-3365 5985);
PAINT MONO (-3365 5985);
DISPLAY INVISIBLE (-3365 5985);
FORCEPROP 1 LASTPIN (-3375 5975) BN 1
J 0
(-3387 5983);
DISPLAY 0.489362 (-3387 5983);
PAINT GREEN (-3387 5983);
FORCEPROP 2 LAST CDS_LIB mstr_standard
J 0
(-3325 5975);
DISPLAY 0.723404 (-3325 5975);
PAINT MONO (-3325 5975);
DISPLAY INVISIBLE (-3325 5975);
FORCEPROP 1 LAST BODY_TYPE PLUMBING
J 0
(-3325 6025);
DISPLAY 0.872340 (-3325 6025);
PAINT GREEN (-3325 6025);
DISPLAY INVISIBLE (-3325 6025);
FORCEPROP 1 LAST HDL_TAP TRUE
J 0
(-3000 5850);
DISPLAY 0.872340 (-3000 5850);
DISPLAY INVISIBLE (-3000 5850);
FORCEPROP 1 LAST PATH I162
J 0
(-3327 5975);
DISPLAY 0.872340 (-3327 5975);
PAINT GREEN (-3327 5975);
DISPLAY INVISIBLE (-3327 5975);
FORCEADD TAP..1
(-3325 5925);
FORCEPROP 3 LASTPIN (-3375 5925) SIG_NAME M_D_CPU1_SA_DQ<2>
J 0
(-3365 5935);
DISPLAY 0.659574 (-3365 5935);
PAINT MONO (-3365 5935);
DISPLAY INVISIBLE (-3365 5935);
FORCEPROP 1 LASTPIN (-3375 5925) BN 2
J 0
(-3387 5933);
DISPLAY 0.489362 (-3387 5933);
PAINT GREEN (-3387 5933);
FORCEPROP 2 LAST CDS_LIB mstr_standard
J 0
(-3325 5925);
DISPLAY 0.723404 (-3325 5925);
PAINT MONO (-3325 5925);
DISPLAY INVISIBLE (-3325 5925);
FORCEPROP 1 LAST BODY_TYPE PLUMBING
J 0
(-3325 5975);
DISPLAY 0.872340 (-3325 5975);
PAINT GREEN (-3325 5975);
DISPLAY INVISIBLE (-3325 5975);
FORCEPROP 1 LAST HDL_TAP TRUE
J 0
(-3000 5800);
DISPLAY 0.872340 (-3000 5800);
DISPLAY INVISIBLE (-3000 5800);
FORCEPROP 1 LAST PATH I163
J 0
(-3327 5925);
DISPLAY 0.872340 (-3327 5925);
PAINT GREEN (-3327 5925);
DISPLAY INVISIBLE (-3327 5925);
FORCEADD TAP..1
(-3325 6025);
FORCEPROP 3 LASTPIN (-3375 6025) SIG_NAME M_D_CPU1_SA_DQ<0>
J 0
(-3365 6035);
DISPLAY 0.659574 (-3365 6035);
PAINT MONO (-3365 6035);
DISPLAY INVISIBLE (-3365 6035);
FORCEPROP 1 LASTPIN (-3375 6025) BN 0
J 0
(-3387 6033);
DISPLAY 0.489362 (-3387 6033);
PAINT GREEN (-3387 6033);
FORCEPROP 2 LAST CDS_LIB mstr_standard
J 0
(-3325 6025);
DISPLAY 0.723404 (-3325 6025);
PAINT MONO (-3325 6025);
DISPLAY INVISIBLE (-3325 6025);
FORCEPROP 1 LAST BODY_TYPE PLUMBING
J 0
(-3325 6075);
DISPLAY 0.872340 (-3325 6075);
PAINT GREEN (-3325 6075);
DISPLAY INVISIBLE (-3325 6075);
FORCEPROP 1 LAST HDL_TAP TRUE
J 0
(-3000 5900);
DISPLAY 0.872340 (-3000 5900);
DISPLAY INVISIBLE (-3000 5900);
FORCEPROP 1 LAST PATH I164
J 0
(-3327 6025);
DISPLAY 0.872340 (-3327 6025);
PAINT GREEN (-3327 6025);
DISPLAY INVISIBLE (-3327 6025);
FORCEADD TAP..1
(-3325 5825);
FORCEPROP 3 LASTPIN (-3375 5825) SIG_NAME M_D_CPU1_SA_DQ<4>
J 0
(-3365 5835);
DISPLAY 0.659574 (-3365 5835);
PAINT MONO (-3365 5835);
DISPLAY INVISIBLE (-3365 5835);
FORCEPROP 1 LASTPIN (-3375 5825) BN 4
J 0
(-3387 5833);
DISPLAY 0.489362 (-3387 5833);
PAINT GREEN (-3387 5833);
FORCEPROP 2 LAST CDS_LIB mstr_standard
J 0
(-3325 5825);
DISPLAY 0.723404 (-3325 5825);
PAINT MONO (-3325 5825);
DISPLAY INVISIBLE (-3325 5825);
FORCEPROP 1 LAST BODY_TYPE PLUMBING
J 0
(-3325 5875);
DISPLAY 0.872340 (-3325 5875);
PAINT GREEN (-3325 5875);
DISPLAY INVISIBLE (-3325 5875);
FORCEPROP 1 LAST HDL_TAP TRUE
J 0
(-3000 5700);
DISPLAY 0.872340 (-3000 5700);
DISPLAY INVISIBLE (-3000 5700);
FORCEPROP 1 LAST PATH I165
J 0
(-3327 5825);
DISPLAY 0.872340 (-3327 5825);
PAINT GREEN (-3327 5825);
DISPLAY INVISIBLE (-3327 5825);
FORCEADD TAP..1
(-3325 5875);
FORCEPROP 3 LASTPIN (-3375 5875) SIG_NAME M_D_CPU1_SA_DQ<3>
J 0
(-3365 5885);
DISPLAY 0.659574 (-3365 5885);
PAINT MONO (-3365 5885);
DISPLAY INVISIBLE (-3365 5885);
FORCEPROP 1 LASTPIN (-3375 5875) BN 3
J 0
(-3387 5883);
DISPLAY 0.489362 (-3387 5883);
PAINT GREEN (-3387 5883);
FORCEPROP 2 LAST CDS_LIB mstr_standard
J 0
(-3325 5875);
DISPLAY 0.723404 (-3325 5875);
PAINT MONO (-3325 5875);
DISPLAY INVISIBLE (-3325 5875);
FORCEPROP 1 LAST BODY_TYPE PLUMBING
J 0
(-3325 5925);
DISPLAY 0.872340 (-3325 5925);
PAINT GREEN (-3325 5925);
DISPLAY INVISIBLE (-3325 5925);
FORCEPROP 1 LAST HDL_TAP TRUE
J 0
(-3000 5750);
DISPLAY 0.872340 (-3000 5750);
DISPLAY INVISIBLE (-3000 5750);
FORCEPROP 1 LAST PATH I166
J 0
(-3327 5875);
DISPLAY 0.872340 (-3327 5875);
PAINT GREEN (-3327 5875);
DISPLAY INVISIBLE (-3327 5875);
FORCEADD TAP..1
(-3325 5775);
FORCEPROP 3 LASTPIN (-3375 5775) SIG_NAME M_D_CPU1_SA_DQ<5>
J 0
(-3365 5785);
DISPLAY 0.659574 (-3365 5785);
PAINT MONO (-3365 5785);
DISPLAY INVISIBLE (-3365 5785);
FORCEPROP 1 LASTPIN (-3375 5775) BN 5
J 0
(-3387 5783);
DISPLAY 0.489362 (-3387 5783);
PAINT GREEN (-3387 5783);
FORCEPROP 2 LAST CDS_LIB mstr_standard
J 0
(-3325 5775);
DISPLAY 0.723404 (-3325 5775);
PAINT MONO (-3325 5775);
DISPLAY INVISIBLE (-3325 5775);
FORCEPROP 1 LAST BODY_TYPE PLUMBING
J 0
(-3325 5825);
DISPLAY 0.872340 (-3325 5825);
PAINT GREEN (-3325 5825);
DISPLAY INVISIBLE (-3325 5825);
FORCEPROP 1 LAST HDL_TAP TRUE
J 0
(-3000 5650);
DISPLAY 0.872340 (-3000 5650);
DISPLAY INVISIBLE (-3000 5650);
FORCEPROP 1 LAST PATH I167
J 0
(-3327 5775);
DISPLAY 0.872340 (-3327 5775);
PAINT GREEN (-3327 5775);
DISPLAY INVISIBLE (-3327 5775);
FORCEADD TAP..1
(-3325 5725);
FORCEPROP 3 LASTPIN (-3375 5725) SIG_NAME M_D_CPU1_SA_DQ<6>
J 0
(-3365 5735);
DISPLAY 0.659574 (-3365 5735);
PAINT MONO (-3365 5735);
DISPLAY INVISIBLE (-3365 5735);
FORCEPROP 1 LASTPIN (-3375 5725) BN 6
J 0
(-3387 5733);
DISPLAY 0.489362 (-3387 5733);
PAINT GREEN (-3387 5733);
FORCEPROP 2 LAST CDS_LIB mstr_standard
J 0
(-3325 5725);
DISPLAY 0.723404 (-3325 5725);
PAINT MONO (-3325 5725);
DISPLAY INVISIBLE (-3325 5725);
FORCEPROP 1 LAST BODY_TYPE PLUMBING
J 0
(-3325 5775);
DISPLAY 0.872340 (-3325 5775);
PAINT GREEN (-3325 5775);
DISPLAY INVISIBLE (-3325 5775);
FORCEPROP 1 LAST HDL_TAP TRUE
J 0
(-3000 5600);
DISPLAY 0.872340 (-3000 5600);
DISPLAY INVISIBLE (-3000 5600);
FORCEPROP 1 LAST PATH I168
J 0
(-3327 5725);
DISPLAY 0.872340 (-3327 5725);
PAINT GREEN (-3327 5725);
DISPLAY INVISIBLE (-3327 5725);
FORCEADD TAP..1
(-3325 5675);
FORCEPROP 3 LASTPIN (-3375 5675) SIG_NAME M_D_CPU1_SA_DQ<7>
J 0
(-3365 5685);
DISPLAY 0.659574 (-3365 5685);
PAINT MONO (-3365 5685);
DISPLAY INVISIBLE (-3365 5685);
FORCEPROP 1 LASTPIN (-3375 5675) BN 7
J 0
(-3387 5683);
DISPLAY 0.489362 (-3387 5683);
PAINT GREEN (-3387 5683);
FORCEPROP 2 LAST CDS_LIB mstr_standard
J 0
(-3325 5675);
DISPLAY 0.723404 (-3325 5675);
PAINT MONO (-3325 5675);
DISPLAY INVISIBLE (-3325 5675);
FORCEPROP 1 LAST BODY_TYPE PLUMBING
J 0
(-3325 5725);
DISPLAY 0.872340 (-3325 5725);
PAINT GREEN (-3325 5725);
DISPLAY INVISIBLE (-3325 5725);
FORCEPROP 1 LAST HDL_TAP TRUE
J 0
(-3000 5550);
DISPLAY 0.872340 (-3000 5550);
DISPLAY INVISIBLE (-3000 5550);
FORCEPROP 1 LAST PATH I169
J 0
(-3327 5675);
DISPLAY 0.872340 (-3327 5675);
PAINT GREEN (-3327 5675);
DISPLAY INVISIBLE (-3327 5675);
FORCEADD TAP..1
(-3325 5425);
FORCEPROP 3 LASTPIN (-3375 5425) SIG_NAME M_D_CPU1_SA_DQ<11>
J 0
(-3365 5435);
DISPLAY 0.659574 (-3365 5435);
PAINT MONO (-3365 5435);
DISPLAY INVISIBLE (-3365 5435);
FORCEPROP 1 LASTPIN (-3375 5425) BN 11
J 0
(-3387 5433);
DISPLAY 0.489362 (-3387 5433);
PAINT GREEN (-3387 5433);
FORCEPROP 2 LAST CDS_LIB mstr_standard
J 0
(-3325 5425);
DISPLAY 0.723404 (-3325 5425);
PAINT MONO (-3325 5425);
DISPLAY INVISIBLE (-3325 5425);
FORCEPROP 1 LAST BODY_TYPE PLUMBING
J 0
(-3325 5475);
DISPLAY 0.872340 (-3325 5475);
PAINT GREEN (-3325 5475);
DISPLAY INVISIBLE (-3325 5475);
FORCEPROP 1 LAST HDL_TAP TRUE
J 0
(-3000 5300);
DISPLAY 0.872340 (-3000 5300);
DISPLAY INVISIBLE (-3000 5300);
FORCEPROP 1 LAST PATH I170
J 0
(-3327 5425);
DISPLAY 0.872340 (-3327 5425);
PAINT GREEN (-3327 5425);
DISPLAY INVISIBLE (-3327 5425);
FORCEADD TAP..1
(-3325 5475);
FORCEPROP 3 LASTPIN (-3375 5475) SIG_NAME M_D_CPU1_SA_DQ<10>
J 0
(-3365 5485);
DISPLAY 0.659574 (-3365 5485);
PAINT MONO (-3365 5485);
DISPLAY INVISIBLE (-3365 5485);
FORCEPROP 1 LASTPIN (-3375 5475) BN 10
J 0
(-3387 5483);
DISPLAY 0.489362 (-3387 5483);
PAINT GREEN (-3387 5483);
FORCEPROP 2 LAST CDS_LIB mstr_standard
J 0
(-3325 5475);
DISPLAY 0.723404 (-3325 5475);
PAINT MONO (-3325 5475);
DISPLAY INVISIBLE (-3325 5475);
FORCEPROP 1 LAST BODY_TYPE PLUMBING
J 0
(-3325 5525);
DISPLAY 0.872340 (-3325 5525);
PAINT GREEN (-3325 5525);
DISPLAY INVISIBLE (-3325 5525);
FORCEPROP 1 LAST HDL_TAP TRUE
J 0
(-3000 5350);
DISPLAY 0.872340 (-3000 5350);
DISPLAY INVISIBLE (-3000 5350);
FORCEPROP 1 LAST PATH I171
J 0
(-3327 5475);
DISPLAY 0.872340 (-3327 5475);
PAINT GREEN (-3327 5475);
DISPLAY INVISIBLE (-3327 5475);
FORCEADD TAP..1
(-3325 5525);
FORCEPROP 3 LASTPIN (-3375 5525) SIG_NAME M_D_CPU1_SA_DQ<9>
J 0
(-3365 5535);
DISPLAY 0.659574 (-3365 5535);
PAINT MONO (-3365 5535);
DISPLAY INVISIBLE (-3365 5535);
FORCEPROP 1 LASTPIN (-3375 5525) BN 9
J 0
(-3387 5533);
DISPLAY 0.489362 (-3387 5533);
PAINT GREEN (-3387 5533);
FORCEPROP 2 LAST CDS_LIB mstr_standard
J 0
(-3325 5525);
DISPLAY 0.723404 (-3325 5525);
PAINT MONO (-3325 5525);
DISPLAY INVISIBLE (-3325 5525);
FORCEPROP 1 LAST BODY_TYPE PLUMBING
J 0
(-3325 5575);
DISPLAY 0.872340 (-3325 5575);
PAINT GREEN (-3325 5575);
DISPLAY INVISIBLE (-3325 5575);
FORCEPROP 1 LAST HDL_TAP TRUE
J 0
(-3000 5400);
DISPLAY 0.872340 (-3000 5400);
DISPLAY INVISIBLE (-3000 5400);
FORCEPROP 1 LAST PATH I172
J 0
(-3327 5525);
DISPLAY 0.872340 (-3327 5525);
PAINT GREEN (-3327 5525);
DISPLAY INVISIBLE (-3327 5525);
FORCEADD TAP..1
(-3325 5575);
FORCEPROP 3 LASTPIN (-3375 5575) SIG_NAME M_D_CPU1_SA_DQ<8>
J 0
(-3365 5585);
DISPLAY 0.659574 (-3365 5585);
PAINT MONO (-3365 5585);
DISPLAY INVISIBLE (-3365 5585);
FORCEPROP 1 LASTPIN (-3375 5575) BN 8
J 0
(-3387 5583);
DISPLAY 0.489362 (-3387 5583);
PAINT GREEN (-3387 5583);
FORCEPROP 2 LAST CDS_LIB mstr_standard
J 0
(-3325 5575);
DISPLAY 0.723404 (-3325 5575);
PAINT MONO (-3325 5575);
DISPLAY INVISIBLE (-3325 5575);
FORCEPROP 1 LAST BODY_TYPE PLUMBING
J 0
(-3325 5625);
DISPLAY 0.872340 (-3325 5625);
PAINT GREEN (-3325 5625);
DISPLAY INVISIBLE (-3325 5625);
FORCEPROP 1 LAST HDL_TAP TRUE
J 0
(-3000 5450);
DISPLAY 0.872340 (-3000 5450);
DISPLAY INVISIBLE (-3000 5450);
FORCEPROP 1 LAST PATH I173
J 0
(-3327 5575);
DISPLAY 0.872340 (-3327 5575);
PAINT GREEN (-3327 5575);
DISPLAY INVISIBLE (-3327 5575);
FORCEADD TAP..1
(-3325 5125);
FORCEPROP 3 LASTPIN (-3375 5125) SIG_NAME M_D_CPU1_SA_DQ<16>
J 0
(-3365 5135);
DISPLAY 0.659574 (-3365 5135);
PAINT MONO (-3365 5135);
DISPLAY INVISIBLE (-3365 5135);
FORCEPROP 1 LASTPIN (-3375 5125) BN 16
J 0
(-3387 5133);
DISPLAY 0.489362 (-3387 5133);
PAINT GREEN (-3387 5133);
FORCEPROP 2 LAST CDS_LIB mstr_standard
J 0
(-3325 5125);
DISPLAY 0.723404 (-3325 5125);
PAINT MONO (-3325 5125);
DISPLAY INVISIBLE (-3325 5125);
FORCEPROP 1 LAST BODY_TYPE PLUMBING
J 0
(-3325 5175);
DISPLAY 0.872340 (-3325 5175);
PAINT GREEN (-3325 5175);
DISPLAY INVISIBLE (-3325 5175);
FORCEPROP 1 LAST HDL_TAP TRUE
J 0
(-3000 5000);
DISPLAY 0.872340 (-3000 5000);
DISPLAY INVISIBLE (-3000 5000);
FORCEPROP 1 LAST PATH I174
J 0
(-3327 5125);
DISPLAY 0.872340 (-3327 5125);
PAINT GREEN (-3327 5125);
DISPLAY INVISIBLE (-3327 5125);
FORCEADD TAP..1
(-3325 5225);
FORCEPROP 3 LASTPIN (-3375 5225) SIG_NAME M_D_CPU1_SA_DQ<15>
J 0
(-3365 5235);
DISPLAY 0.659574 (-3365 5235);
PAINT MONO (-3365 5235);
DISPLAY INVISIBLE (-3365 5235);
FORCEPROP 1 LASTPIN (-3375 5225) BN 15
J 0
(-3387 5233);
DISPLAY 0.489362 (-3387 5233);
PAINT GREEN (-3387 5233);
FORCEPROP 2 LAST CDS_LIB mstr_standard
J 0
(-3325 5225);
DISPLAY 0.723404 (-3325 5225);
PAINT MONO (-3325 5225);
DISPLAY INVISIBLE (-3325 5225);
FORCEPROP 1 LAST BODY_TYPE PLUMBING
J 0
(-3325 5275);
DISPLAY 0.872340 (-3325 5275);
PAINT GREEN (-3325 5275);
DISPLAY INVISIBLE (-3325 5275);
FORCEPROP 1 LAST HDL_TAP TRUE
J 0
(-3000 5100);
DISPLAY 0.872340 (-3000 5100);
DISPLAY INVISIBLE (-3000 5100);
FORCEPROP 1 LAST PATH I175
J 0
(-3327 5225);
DISPLAY 0.872340 (-3327 5225);
PAINT GREEN (-3327 5225);
DISPLAY INVISIBLE (-3327 5225);
FORCEADD TAP..1
(-3325 5275);
FORCEPROP 3 LASTPIN (-3375 5275) SIG_NAME M_D_CPU1_SA_DQ<14>
J 0
(-3365 5285);
DISPLAY 0.659574 (-3365 5285);
PAINT MONO (-3365 5285);
DISPLAY INVISIBLE (-3365 5285);
FORCEPROP 1 LASTPIN (-3375 5275) BN 14
J 0
(-3387 5283);
DISPLAY 0.489362 (-3387 5283);
PAINT GREEN (-3387 5283);
FORCEPROP 2 LAST CDS_LIB mstr_standard
J 0
(-3325 5275);
DISPLAY 0.723404 (-3325 5275);
PAINT MONO (-3325 5275);
DISPLAY INVISIBLE (-3325 5275);
FORCEPROP 1 LAST BODY_TYPE PLUMBING
J 0
(-3325 5325);
DISPLAY 0.872340 (-3325 5325);
PAINT GREEN (-3325 5325);
DISPLAY INVISIBLE (-3325 5325);
FORCEPROP 1 LAST HDL_TAP TRUE
J 0
(-3000 5150);
DISPLAY 0.872340 (-3000 5150);
DISPLAY INVISIBLE (-3000 5150);
FORCEPROP 1 LAST PATH I176
J 0
(-3327 5275);
DISPLAY 0.872340 (-3327 5275);
PAINT GREEN (-3327 5275);
DISPLAY INVISIBLE (-3327 5275);
FORCEADD TAP..1
(-3325 5375);
FORCEPROP 3 LASTPIN (-3375 5375) SIG_NAME M_D_CPU1_SA_DQ<12>
J 0
(-3365 5385);
DISPLAY 0.659574 (-3365 5385);
PAINT MONO (-3365 5385);
DISPLAY INVISIBLE (-3365 5385);
FORCEPROP 1 LASTPIN (-3375 5375) BN 12
J 0
(-3387 5383);
DISPLAY 0.489362 (-3387 5383);
PAINT GREEN (-3387 5383);
FORCEPROP 2 LAST CDS_LIB mstr_standard
J 0
(-3325 5375);
DISPLAY 0.723404 (-3325 5375);
PAINT MONO (-3325 5375);
DISPLAY INVISIBLE (-3325 5375);
FORCEPROP 1 LAST BODY_TYPE PLUMBING
J 0
(-3325 5425);
DISPLAY 0.872340 (-3325 5425);
PAINT GREEN (-3325 5425);
DISPLAY INVISIBLE (-3325 5425);
FORCEPROP 1 LAST HDL_TAP TRUE
J 0
(-3000 5250);
DISPLAY 0.872340 (-3000 5250);
DISPLAY INVISIBLE (-3000 5250);
FORCEPROP 1 LAST PATH I177
J 0
(-3327 5375);
DISPLAY 0.872340 (-3327 5375);
PAINT GREEN (-3327 5375);
DISPLAY INVISIBLE (-3327 5375);
FORCEADD TAP..1
(-3325 5325);
FORCEPROP 3 LASTPIN (-3375 5325) SIG_NAME M_D_CPU1_SA_DQ<13>
J 0
(-3365 5335);
DISPLAY 0.659574 (-3365 5335);
PAINT MONO (-3365 5335);
DISPLAY INVISIBLE (-3365 5335);
FORCEPROP 1 LASTPIN (-3375 5325) BN 13
J 0
(-3387 5333);
DISPLAY 0.489362 (-3387 5333);
PAINT GREEN (-3387 5333);
FORCEPROP 2 LAST CDS_LIB mstr_standard
J 0
(-3325 5325);
DISPLAY 0.723404 (-3325 5325);
PAINT MONO (-3325 5325);
DISPLAY INVISIBLE (-3325 5325);
FORCEPROP 1 LAST BODY_TYPE PLUMBING
J 0
(-3325 5375);
DISPLAY 0.872340 (-3325 5375);
PAINT GREEN (-3325 5375);
DISPLAY INVISIBLE (-3325 5375);
FORCEPROP 1 LAST HDL_TAP TRUE
J 0
(-3000 5200);
DISPLAY 0.872340 (-3000 5200);
DISPLAY INVISIBLE (-3000 5200);
FORCEPROP 1 LAST PATH I178
J 0
(-3327 5325);
DISPLAY 0.872340 (-3327 5325);
PAINT GREEN (-3327 5325);
DISPLAY INVISIBLE (-3327 5325);
FORCEADD TAP..1
(-3325 4925);
FORCEPROP 3 LASTPIN (-3375 4925) SIG_NAME M_D_CPU1_SA_DQ<20>
J 0
(-3365 4935);
DISPLAY 0.659574 (-3365 4935);
PAINT MONO (-3365 4935);
DISPLAY INVISIBLE (-3365 4935);
FORCEPROP 1 LASTPIN (-3375 4925) BN 20
J 0
(-3387 4933);
DISPLAY 0.489362 (-3387 4933);
PAINT GREEN (-3387 4933);
FORCEPROP 2 LAST CDS_LIB mstr_standard
J 0
(-3325 4925);
DISPLAY 0.723404 (-3325 4925);
PAINT MONO (-3325 4925);
DISPLAY INVISIBLE (-3325 4925);
FORCEPROP 1 LAST BODY_TYPE PLUMBING
J 0
(-3325 4975);
DISPLAY 0.872340 (-3325 4975);
PAINT GREEN (-3325 4975);
DISPLAY INVISIBLE (-3325 4975);
FORCEPROP 1 LAST HDL_TAP TRUE
J 0
(-3000 4800);
DISPLAY 0.872340 (-3000 4800);
DISPLAY INVISIBLE (-3000 4800);
FORCEPROP 1 LAST PATH I179
J 0
(-3327 4925);
DISPLAY 0.872340 (-3327 4925);
PAINT GREEN (-3327 4925);
DISPLAY INVISIBLE (-3327 4925);
FORCEADD TAP..1
(-3325 4875);
FORCEPROP 3 LASTPIN (-3375 4875) SIG_NAME M_D_CPU1_SA_DQ<21>
J 0
(-3365 4885);
DISPLAY 0.659574 (-3365 4885);
PAINT MONO (-3365 4885);
DISPLAY INVISIBLE (-3365 4885);
FORCEPROP 1 LASTPIN (-3375 4875) BN 21
J 0
(-3387 4883);
DISPLAY 0.489362 (-3387 4883);
PAINT GREEN (-3387 4883);
FORCEPROP 2 LAST CDS_LIB mstr_standard
J 0
(-3325 4875);
DISPLAY 0.723404 (-3325 4875);
PAINT MONO (-3325 4875);
DISPLAY INVISIBLE (-3325 4875);
FORCEPROP 1 LAST BODY_TYPE PLUMBING
J 0
(-3325 4925);
DISPLAY 0.872340 (-3325 4925);
PAINT GREEN (-3325 4925);
DISPLAY INVISIBLE (-3325 4925);
FORCEPROP 1 LAST HDL_TAP TRUE
J 0
(-3000 4750);
DISPLAY 0.872340 (-3000 4750);
DISPLAY INVISIBLE (-3000 4750);
FORCEPROP 1 LAST PATH I180
J 0
(-3327 4875);
DISPLAY 0.872340 (-3327 4875);
PAINT GREEN (-3327 4875);
DISPLAY INVISIBLE (-3327 4875);
FORCEADD TAP..1
(-3325 4975);
FORCEPROP 3 LASTPIN (-3375 4975) SIG_NAME M_D_CPU1_SA_DQ<19>
J 0
(-3365 4985);
DISPLAY 0.659574 (-3365 4985);
PAINT MONO (-3365 4985);
DISPLAY INVISIBLE (-3365 4985);
FORCEPROP 1 LASTPIN (-3375 4975) BN 19
J 0
(-3387 4983);
DISPLAY 0.489362 (-3387 4983);
PAINT GREEN (-3387 4983);
FORCEPROP 2 LAST CDS_LIB mstr_standard
J 0
(-3325 4975);
DISPLAY 0.723404 (-3325 4975);
PAINT MONO (-3325 4975);
DISPLAY INVISIBLE (-3325 4975);
FORCEPROP 1 LAST BODY_TYPE PLUMBING
J 0
(-3325 5025);
DISPLAY 0.872340 (-3325 5025);
PAINT GREEN (-3325 5025);
DISPLAY INVISIBLE (-3325 5025);
FORCEPROP 1 LAST HDL_TAP TRUE
J 0
(-3000 4850);
DISPLAY 0.872340 (-3000 4850);
DISPLAY INVISIBLE (-3000 4850);
FORCEPROP 1 LAST PATH I181
J 0
(-3327 4975);
DISPLAY 0.872340 (-3327 4975);
PAINT GREEN (-3327 4975);
DISPLAY INVISIBLE (-3327 4975);
FORCEADD TAP..1
(-3325 5025);
FORCEPROP 3 LASTPIN (-3375 5025) SIG_NAME M_D_CPU1_SA_DQ<18>
J 0
(-3365 5035);
DISPLAY 0.659574 (-3365 5035);
PAINT MONO (-3365 5035);
DISPLAY INVISIBLE (-3365 5035);
FORCEPROP 1 LASTPIN (-3375 5025) BN 18
J 0
(-3387 5033);
DISPLAY 0.489362 (-3387 5033);
PAINT GREEN (-3387 5033);
FORCEPROP 2 LAST CDS_LIB mstr_standard
J 0
(-3325 5025);
DISPLAY 0.723404 (-3325 5025);
PAINT MONO (-3325 5025);
DISPLAY INVISIBLE (-3325 5025);
FORCEPROP 1 LAST BODY_TYPE PLUMBING
J 0
(-3325 5075);
DISPLAY 0.872340 (-3325 5075);
PAINT GREEN (-3325 5075);
DISPLAY INVISIBLE (-3325 5075);
FORCEPROP 1 LAST HDL_TAP TRUE
J 0
(-3000 4900);
DISPLAY 0.872340 (-3000 4900);
DISPLAY INVISIBLE (-3000 4900);
FORCEPROP 1 LAST PATH I182
J 0
(-3327 5025);
DISPLAY 0.872340 (-3327 5025);
PAINT GREEN (-3327 5025);
DISPLAY INVISIBLE (-3327 5025);
FORCEADD TAP..1
(-3325 5075);
FORCEPROP 3 LASTPIN (-3375 5075) SIG_NAME M_D_CPU1_SA_DQ<17>
J 0
(-3365 5085);
DISPLAY 0.659574 (-3365 5085);
PAINT MONO (-3365 5085);
DISPLAY INVISIBLE (-3365 5085);
FORCEPROP 1 LASTPIN (-3375 5075) BN 17
J 0
(-3387 5083);
DISPLAY 0.489362 (-3387 5083);
PAINT GREEN (-3387 5083);
FORCEPROP 2 LAST CDS_LIB mstr_standard
J 0
(-3325 5075);
DISPLAY 0.723404 (-3325 5075);
PAINT MONO (-3325 5075);
DISPLAY INVISIBLE (-3325 5075);
FORCEPROP 1 LAST BODY_TYPE PLUMBING
J 0
(-3325 5125);
DISPLAY 0.872340 (-3325 5125);
PAINT GREEN (-3325 5125);
DISPLAY INVISIBLE (-3325 5125);
FORCEPROP 1 LAST HDL_TAP TRUE
J 0
(-3000 4950);
DISPLAY 0.872340 (-3000 4950);
DISPLAY INVISIBLE (-3000 4950);
FORCEPROP 1 LAST PATH I183
J 0
(-3327 5075);
DISPLAY 0.872340 (-3327 5075);
PAINT GREEN (-3327 5075);
DISPLAY INVISIBLE (-3327 5075);
FORCEADD TAP..1
(-3325 4825);
FORCEPROP 3 LASTPIN (-3375 4825) SIG_NAME M_D_CPU1_SA_DQ<22>
J 0
(-3365 4835);
DISPLAY 0.659574 (-3365 4835);
PAINT MONO (-3365 4835);
DISPLAY INVISIBLE (-3365 4835);
FORCEPROP 1 LASTPIN (-3375 4825) BN 22
J 0
(-3387 4833);
DISPLAY 0.489362 (-3387 4833);
PAINT GREEN (-3387 4833);
FORCEPROP 2 LAST CDS_LIB mstr_standard
J 0
(-3325 4825);
DISPLAY 0.723404 (-3325 4825);
PAINT MONO (-3325 4825);
DISPLAY INVISIBLE (-3325 4825);
FORCEPROP 1 LAST BODY_TYPE PLUMBING
J 0
(-3325 4875);
DISPLAY 0.872340 (-3325 4875);
PAINT GREEN (-3325 4875);
DISPLAY INVISIBLE (-3325 4875);
FORCEPROP 1 LAST HDL_TAP TRUE
J 0
(-3000 4700);
DISPLAY 0.872340 (-3000 4700);
DISPLAY INVISIBLE (-3000 4700);
FORCEPROP 1 LAST PATH I184
J 0
(-3327 4825);
DISPLAY 0.872340 (-3327 4825);
PAINT GREEN (-3327 4825);
DISPLAY INVISIBLE (-3327 4825);
FORCEADD TAP..1
(-3325 4775);
FORCEPROP 3 LASTPIN (-3375 4775) SIG_NAME M_D_CPU1_SA_DQ<23>
J 0
(-3365 4785);
DISPLAY 0.659574 (-3365 4785);
PAINT MONO (-3365 4785);
DISPLAY INVISIBLE (-3365 4785);
FORCEPROP 1 LASTPIN (-3375 4775) BN 23
J 0
(-3387 4783);
DISPLAY 0.489362 (-3387 4783);
PAINT GREEN (-3387 4783);
FORCEPROP 2 LAST CDS_LIB mstr_standard
J 0
(-3325 4775);
DISPLAY 0.723404 (-3325 4775);
PAINT MONO (-3325 4775);
DISPLAY INVISIBLE (-3325 4775);
FORCEPROP 1 LAST BODY_TYPE PLUMBING
J 0
(-3325 4825);
DISPLAY 0.872340 (-3325 4825);
PAINT GREEN (-3325 4825);
DISPLAY INVISIBLE (-3325 4825);
FORCEPROP 1 LAST HDL_TAP TRUE
J 0
(-3000 4650);
DISPLAY 0.872340 (-3000 4650);
DISPLAY INVISIBLE (-3000 4650);
FORCEPROP 1 LAST PATH I185
J 0
(-3327 4775);
DISPLAY 0.872340 (-3327 4775);
PAINT GREEN (-3327 4775);
DISPLAY INVISIBLE (-3327 4775);
FORCEADD TAP..1
(-3325 4675);
FORCEPROP 3 LASTPIN (-3375 4675) SIG_NAME M_D_CPU1_SA_DQ<24>
J 0
(-3365 4685);
DISPLAY 0.659574 (-3365 4685);
PAINT MONO (-3365 4685);
DISPLAY INVISIBLE (-3365 4685);
FORCEPROP 1 LASTPIN (-3375 4675) BN 24
J 0
(-3387 4683);
DISPLAY 0.489362 (-3387 4683);
PAINT GREEN (-3387 4683);
FORCEPROP 2 LAST CDS_LIB mstr_standard
J 0
(-3325 4675);
DISPLAY 0.723404 (-3325 4675);
PAINT MONO (-3325 4675);
DISPLAY INVISIBLE (-3325 4675);
FORCEPROP 1 LAST BODY_TYPE PLUMBING
J 0
(-3325 4725);
DISPLAY 0.872340 (-3325 4725);
PAINT GREEN (-3325 4725);
DISPLAY INVISIBLE (-3325 4725);
FORCEPROP 1 LAST HDL_TAP TRUE
J 0
(-3000 4550);
DISPLAY 0.872340 (-3000 4550);
DISPLAY INVISIBLE (-3000 4550);
FORCEPROP 1 LAST PATH I186
J 0
(-3327 4675);
DISPLAY 0.872340 (-3327 4675);
PAINT GREEN (-3327 4675);
DISPLAY INVISIBLE (-3327 4675);
FORCEADD TAP..1
(-3325 4625);
FORCEPROP 3 LASTPIN (-3375 4625) SIG_NAME M_D_CPU1_SA_DQ<25>
J 0
(-3365 4635);
DISPLAY 0.659574 (-3365 4635);
PAINT MONO (-3365 4635);
DISPLAY INVISIBLE (-3365 4635);
FORCEPROP 1 LASTPIN (-3375 4625) BN 25
J 0
(-3387 4633);
DISPLAY 0.489362 (-3387 4633);
PAINT GREEN (-3387 4633);
FORCEPROP 2 LAST CDS_LIB mstr_standard
J 0
(-3325 4625);
DISPLAY 0.723404 (-3325 4625);
PAINT MONO (-3325 4625);
DISPLAY INVISIBLE (-3325 4625);
FORCEPROP 1 LAST BODY_TYPE PLUMBING
J 0
(-3325 4675);
DISPLAY 0.872340 (-3325 4675);
PAINT GREEN (-3325 4675);
DISPLAY INVISIBLE (-3325 4675);
FORCEPROP 1 LAST HDL_TAP TRUE
J 0
(-3000 4500);
DISPLAY 0.872340 (-3000 4500);
DISPLAY INVISIBLE (-3000 4500);
FORCEPROP 1 LAST PATH I187
J 0
(-3327 4625);
DISPLAY 0.872340 (-3327 4625);
PAINT GREEN (-3327 4625);
DISPLAY INVISIBLE (-3327 4625);
FORCEADD TAP..1
(-3325 4425);
FORCEPROP 3 LASTPIN (-3375 4425) SIG_NAME M_D_CPU1_SA_DQ<29>
J 0
(-3365 4435);
DISPLAY 0.659574 (-3365 4435);
PAINT MONO (-3365 4435);
DISPLAY INVISIBLE (-3365 4435);
FORCEPROP 1 LASTPIN (-3375 4425) BN 29
J 0
(-3387 4433);
DISPLAY 0.489362 (-3387 4433);
PAINT GREEN (-3387 4433);
FORCEPROP 2 LAST CDS_LIB mstr_standard
J 0
(-3325 4425);
DISPLAY 0.723404 (-3325 4425);
PAINT MONO (-3325 4425);
DISPLAY INVISIBLE (-3325 4425);
FORCEPROP 1 LAST BODY_TYPE PLUMBING
J 0
(-3325 4475);
DISPLAY 0.872340 (-3325 4475);
PAINT GREEN (-3325 4475);
DISPLAY INVISIBLE (-3325 4475);
FORCEPROP 1 LAST HDL_TAP TRUE
J 0
(-3000 4300);
DISPLAY 0.872340 (-3000 4300);
DISPLAY INVISIBLE (-3000 4300);
FORCEPROP 1 LAST PATH I188
J 0
(-3327 4425);
DISPLAY 0.872340 (-3327 4425);
PAINT GREEN (-3327 4425);
DISPLAY INVISIBLE (-3327 4425);
FORCEADD TAP..1
(-3325 4375);
FORCEPROP 3 LASTPIN (-3375 4375) SIG_NAME M_D_CPU1_SA_DQ<30>
J 0
(-3365 4385);
DISPLAY 0.659574 (-3365 4385);
PAINT MONO (-3365 4385);
DISPLAY INVISIBLE (-3365 4385);
FORCEPROP 1 LASTPIN (-3375 4375) BN 30
J 0
(-3387 4383);
DISPLAY 0.489362 (-3387 4383);
PAINT GREEN (-3387 4383);
FORCEPROP 2 LAST CDS_LIB mstr_standard
J 0
(-3325 4375);
DISPLAY 0.723404 (-3325 4375);
PAINT MONO (-3325 4375);
DISPLAY INVISIBLE (-3325 4375);
FORCEPROP 1 LAST BODY_TYPE PLUMBING
J 0
(-3325 4425);
DISPLAY 0.872340 (-3325 4425);
PAINT GREEN (-3325 4425);
DISPLAY INVISIBLE (-3325 4425);
FORCEPROP 1 LAST HDL_TAP TRUE
J 0
(-3000 4250);
DISPLAY 0.872340 (-3000 4250);
DISPLAY INVISIBLE (-3000 4250);
FORCEPROP 1 LAST PATH I189
J 0
(-3327 4375);
DISPLAY 0.872340 (-3327 4375);
PAINT GREEN (-3327 4375);
DISPLAY INVISIBLE (-3327 4375);
FORCEADD TAP..1
(-3325 4475);
FORCEPROP 3 LASTPIN (-3375 4475) SIG_NAME M_D_CPU1_SA_DQ<28>
J 0
(-3365 4485);
DISPLAY 0.659574 (-3365 4485);
PAINT MONO (-3365 4485);
DISPLAY INVISIBLE (-3365 4485);
FORCEPROP 1 LASTPIN (-3375 4475) BN 28
J 0
(-3387 4483);
DISPLAY 0.489362 (-3387 4483);
PAINT GREEN (-3387 4483);
FORCEPROP 2 LAST CDS_LIB mstr_standard
J 0
(-3325 4475);
DISPLAY 0.723404 (-3325 4475);
PAINT MONO (-3325 4475);
DISPLAY INVISIBLE (-3325 4475);
FORCEPROP 1 LAST BODY_TYPE PLUMBING
J 0
(-3325 4525);
DISPLAY 0.872340 (-3325 4525);
PAINT GREEN (-3325 4525);
DISPLAY INVISIBLE (-3325 4525);
FORCEPROP 1 LAST HDL_TAP TRUE
J 0
(-3000 4350);
DISPLAY 0.872340 (-3000 4350);
DISPLAY INVISIBLE (-3000 4350);
FORCEPROP 1 LAST PATH I190
J 0
(-3327 4475);
DISPLAY 0.872340 (-3327 4475);
PAINT GREEN (-3327 4475);
DISPLAY INVISIBLE (-3327 4475);
FORCEADD TAP..1
(-3325 4575);
FORCEPROP 3 LASTPIN (-3375 4575) SIG_NAME M_D_CPU1_SA_DQ<26>
J 0
(-3365 4585);
DISPLAY 0.659574 (-3365 4585);
PAINT MONO (-3365 4585);
DISPLAY INVISIBLE (-3365 4585);
FORCEPROP 1 LASTPIN (-3375 4575) BN 26
J 0
(-3387 4583);
DISPLAY 0.489362 (-3387 4583);
PAINT GREEN (-3387 4583);
FORCEPROP 2 LAST CDS_LIB mstr_standard
J 0
(-3325 4575);
DISPLAY 0.723404 (-3325 4575);
PAINT MONO (-3325 4575);
DISPLAY INVISIBLE (-3325 4575);
FORCEPROP 1 LAST BODY_TYPE PLUMBING
J 0
(-3325 4625);
DISPLAY 0.872340 (-3325 4625);
PAINT GREEN (-3325 4625);
DISPLAY INVISIBLE (-3325 4625);
FORCEPROP 1 LAST HDL_TAP TRUE
J 0
(-3000 4450);
DISPLAY 0.872340 (-3000 4450);
DISPLAY INVISIBLE (-3000 4450);
FORCEPROP 1 LAST PATH I191
J 0
(-3327 4575);
DISPLAY 0.872340 (-3327 4575);
PAINT GREEN (-3327 4575);
DISPLAY INVISIBLE (-3327 4575);
FORCEADD TAP..1
(-3325 4525);
FORCEPROP 3 LASTPIN (-3375 4525) SIG_NAME M_D_CPU1_SA_DQ<27>
J 0
(-3365 4535);
DISPLAY 0.659574 (-3365 4535);
PAINT MONO (-3365 4535);
DISPLAY INVISIBLE (-3365 4535);
FORCEPROP 1 LASTPIN (-3375 4525) BN 27
J 0
(-3387 4533);
DISPLAY 0.489362 (-3387 4533);
PAINT GREEN (-3387 4533);
FORCEPROP 2 LAST CDS_LIB mstr_standard
J 0
(-3325 4525);
DISPLAY 0.723404 (-3325 4525);
PAINT MONO (-3325 4525);
DISPLAY INVISIBLE (-3325 4525);
FORCEPROP 1 LAST BODY_TYPE PLUMBING
J 0
(-3325 4575);
DISPLAY 0.872340 (-3325 4575);
PAINT GREEN (-3325 4575);
DISPLAY INVISIBLE (-3325 4575);
FORCEPROP 1 LAST HDL_TAP TRUE
J 0
(-3000 4400);
DISPLAY 0.872340 (-3000 4400);
DISPLAY INVISIBLE (-3000 4400);
FORCEPROP 1 LAST PATH I192
J 0
(-3327 4525);
DISPLAY 0.872340 (-3327 4525);
PAINT GREEN (-3327 4525);
DISPLAY INVISIBLE (-3327 4525);
FORCEADD TAP..1
(-3325 4175);
FORCEPROP 3 LASTPIN (-3375 4175) SIG_NAME M_D_CPU1_SB_DQ<1>
J 0
(-3365 4185);
DISPLAY 0.659574 (-3365 4185);
PAINT MONO (-3365 4185);
DISPLAY INVISIBLE (-3365 4185);
FORCEPROP 1 LASTPIN (-3375 4175) BN 1
J 0
(-3387 4183);
DISPLAY 0.489362 (-3387 4183);
PAINT GREEN (-3387 4183);
FORCEPROP 2 LAST CDS_LIB mstr_standard
J 0
(-3325 4175);
DISPLAY 0.723404 (-3325 4175);
PAINT MONO (-3325 4175);
DISPLAY INVISIBLE (-3325 4175);
FORCEPROP 1 LAST BODY_TYPE PLUMBING
J 0
(-3325 4225);
DISPLAY 0.872340 (-3325 4225);
PAINT GREEN (-3325 4225);
DISPLAY INVISIBLE (-3325 4225);
FORCEPROP 1 LAST HDL_TAP TRUE
J 0
(-3000 4050);
DISPLAY 0.872340 (-3000 4050);
DISPLAY INVISIBLE (-3000 4050);
FORCEPROP 1 LAST PATH I193
J 0
(-3327 4175);
DISPLAY 0.872340 (-3327 4175);
PAINT GREEN (-3327 4175);
DISPLAY INVISIBLE (-3327 4175);
FORCEADD TAP..1
(-3325 4325);
FORCEPROP 3 LASTPIN (-3375 4325) SIG_NAME M_D_CPU1_SA_DQ<31>
J 0
(-3365 4335);
DISPLAY 0.659574 (-3365 4335);
PAINT MONO (-3365 4335);
DISPLAY INVISIBLE (-3365 4335);
FORCEPROP 1 LASTPIN (-3375 4325) BN 31
J 0
(-3387 4333);
DISPLAY 0.489362 (-3387 4333);
PAINT GREEN (-3387 4333);
FORCEPROP 2 LAST CDS_LIB mstr_standard
J 0
(-3325 4325);
DISPLAY 0.723404 (-3325 4325);
PAINT MONO (-3325 4325);
DISPLAY INVISIBLE (-3325 4325);
FORCEPROP 1 LAST BODY_TYPE PLUMBING
J 0
(-3325 4375);
DISPLAY 0.872340 (-3325 4375);
PAINT GREEN (-3325 4375);
DISPLAY INVISIBLE (-3325 4375);
FORCEPROP 1 LAST HDL_TAP TRUE
J 0
(-3000 4200);
DISPLAY 0.872340 (-3000 4200);
DISPLAY INVISIBLE (-3000 4200);
FORCEPROP 1 LAST PATH I194
J 0
(-3327 4325);
DISPLAY 0.872340 (-3327 4325);
PAINT GREEN (-3327 4325);
DISPLAY INVISIBLE (-3327 4325);
FORCEADD TAP..1
(-3325 4125);
FORCEPROP 3 LASTPIN (-3375 4125) SIG_NAME M_D_CPU1_SB_DQ<2>
J 0
(-3365 4135);
DISPLAY 0.659574 (-3365 4135);
PAINT MONO (-3365 4135);
DISPLAY INVISIBLE (-3365 4135);
FORCEPROP 1 LASTPIN (-3375 4125) BN 2
J 0
(-3387 4133);
DISPLAY 0.489362 (-3387 4133);
PAINT GREEN (-3387 4133);
FORCEPROP 2 LAST CDS_LIB mstr_standard
J 0
(-3325 4125);
DISPLAY 0.723404 (-3325 4125);
PAINT MONO (-3325 4125);
DISPLAY INVISIBLE (-3325 4125);
FORCEPROP 1 LAST BODY_TYPE PLUMBING
J 0
(-3325 4175);
DISPLAY 0.872340 (-3325 4175);
PAINT GREEN (-3325 4175);
DISPLAY INVISIBLE (-3325 4175);
FORCEPROP 1 LAST HDL_TAP TRUE
J 0
(-3000 4000);
DISPLAY 0.872340 (-3000 4000);
DISPLAY INVISIBLE (-3000 4000);
FORCEPROP 1 LAST PATH I195
J 0
(-3327 4125);
DISPLAY 0.872340 (-3327 4125);
PAINT GREEN (-3327 4125);
DISPLAY INVISIBLE (-3327 4125);
FORCEADD TAP..1
(-3325 4225);
FORCEPROP 3 LASTPIN (-3375 4225) SIG_NAME M_D_CPU1_SB_DQ<0>
J 0
(-3365 4235);
DISPLAY 0.659574 (-3365 4235);
PAINT MONO (-3365 4235);
DISPLAY INVISIBLE (-3365 4235);
FORCEPROP 1 LASTPIN (-3375 4225) BN 0
J 0
(-3387 4233);
DISPLAY 0.489362 (-3387 4233);
PAINT GREEN (-3387 4233);
FORCEPROP 2 LAST CDS_LIB mstr_standard
J 0
(-3325 4225);
DISPLAY 0.723404 (-3325 4225);
PAINT MONO (-3325 4225);
DISPLAY INVISIBLE (-3325 4225);
FORCEPROP 1 LAST BODY_TYPE PLUMBING
J 0
(-3325 4275);
DISPLAY 0.872340 (-3325 4275);
PAINT GREEN (-3325 4275);
DISPLAY INVISIBLE (-3325 4275);
FORCEPROP 1 LAST HDL_TAP TRUE
J 0
(-3000 4100);
DISPLAY 0.872340 (-3000 4100);
DISPLAY INVISIBLE (-3000 4100);
FORCEPROP 1 LAST PATH I196
J 0
(-3327 4225);
DISPLAY 0.872340 (-3327 4225);
PAINT GREEN (-3327 4225);
DISPLAY INVISIBLE (-3327 4225);
FORCEADD OFFPAGE..6
R 2
(-2725 2475);
FORCEPROP 2 LAST $XR0 101 
J 0
(-2511 2475);
DISPLAY 0.638298 (-2511 2475);
PAINT MONO (-2511 2475);
FORCEPROP 2 LAST CDS_LIB mstr_standard
J 2
(-2725 2475);
DISPLAY 0.723404 (-2725 2475);
PAINT MONO (-2725 2475);
DISPLAY INVISIBLE (-2725 2475);
FORCEPROP 1 LAST OFFPAGE TRUE
J 2
(-3050 2350);
DISPLAY 0.872340 (-3050 2350);
PAINT GREEN (-3050 2350);
DISPLAY INVISIBLE (-3050 2350);
FORCEPROP 1 LAST COMMENT_BODY TRUE
J 2
(-2825 2400);
DISPLAY 0.872340 (-2825 2400);
PAINT GREEN (-2825 2400);
DISPLAY INVISIBLE (-2825 2400);
FORCEPROP 2 LAST PATH I197
J 0
(-2500 2525);
DISPLAY 1.021277 (-2500 2525);
DISPLAY INVISIBLE (-2500 2525);
FORCEADD TAP..1
(-3325 4025);
FORCEPROP 3 LASTPIN (-3375 4025) SIG_NAME M_D_CPU1_SB_DQ<4>
J 0
(-3365 4035);
DISPLAY 0.659574 (-3365 4035);
PAINT MONO (-3365 4035);
DISPLAY INVISIBLE (-3365 4035);
FORCEPROP 1 LASTPIN (-3375 4025) BN 4
J 0
(-3387 4033);
DISPLAY 0.489362 (-3387 4033);
PAINT GREEN (-3387 4033);
FORCEPROP 2 LAST CDS_LIB mstr_standard
J 0
(-3325 4025);
DISPLAY 0.723404 (-3325 4025);
PAINT MONO (-3325 4025);
DISPLAY INVISIBLE (-3325 4025);
FORCEPROP 1 LAST BODY_TYPE PLUMBING
J 0
(-3325 4075);
DISPLAY 0.872340 (-3325 4075);
PAINT GREEN (-3325 4075);
DISPLAY INVISIBLE (-3325 4075);
FORCEPROP 1 LAST HDL_TAP TRUE
J 0
(-3000 3900);
DISPLAY 0.872340 (-3000 3900);
DISPLAY INVISIBLE (-3000 3900);
FORCEPROP 1 LAST PATH I198
J 0
(-3327 4025);
DISPLAY 0.872340 (-3327 4025);
PAINT GREEN (-3327 4025);
DISPLAY INVISIBLE (-3327 4025);
FORCEADD TAP..1
(-3325 4075);
FORCEPROP 3 LASTPIN (-3375 4075) SIG_NAME M_D_CPU1_SB_DQ<3>
J 0
(-3365 4085);
DISPLAY 0.659574 (-3365 4085);
PAINT MONO (-3365 4085);
DISPLAY INVISIBLE (-3365 4085);
FORCEPROP 1 LASTPIN (-3375 4075) BN 3
J 0
(-3387 4083);
DISPLAY 0.489362 (-3387 4083);
PAINT GREEN (-3387 4083);
FORCEPROP 2 LAST CDS_LIB mstr_standard
J 0
(-3325 4075);
DISPLAY 0.723404 (-3325 4075);
PAINT MONO (-3325 4075);
DISPLAY INVISIBLE (-3325 4075);
FORCEPROP 1 LAST BODY_TYPE PLUMBING
J 0
(-3325 4125);
DISPLAY 0.872340 (-3325 4125);
PAINT GREEN (-3325 4125);
DISPLAY INVISIBLE (-3325 4125);
FORCEPROP 1 LAST HDL_TAP TRUE
J 0
(-3000 3950);
DISPLAY 0.872340 (-3000 3950);
DISPLAY INVISIBLE (-3000 3950);
FORCEPROP 1 LAST PATH I199
J 0
(-3327 4075);
DISPLAY 0.872340 (-3327 4075);
PAINT GREEN (-3327 4075);
DISPLAY INVISIBLE (-3327 4075);
FORCEADD TAP..1
(-3325 3975);
FORCEPROP 3 LASTPIN (-3375 3975) SIG_NAME M_D_CPU1_SB_DQ<5>
J 0
(-3365 3985);
DISPLAY 0.659574 (-3365 3985);
PAINT MONO (-3365 3985);
DISPLAY INVISIBLE (-3365 3985);
FORCEPROP 1 LASTPIN (-3375 3975) BN 5
J 0
(-3387 3983);
DISPLAY 0.489362 (-3387 3983);
PAINT GREEN (-3387 3983);
FORCEPROP 2 LAST CDS_LIB mstr_standard
J 0
(-3325 3975);
DISPLAY 0.723404 (-3325 3975);
PAINT MONO (-3325 3975);
DISPLAY INVISIBLE (-3325 3975);
FORCEPROP 1 LAST BODY_TYPE PLUMBING
J 0
(-3325 4025);
DISPLAY 0.872340 (-3325 4025);
PAINT GREEN (-3325 4025);
DISPLAY INVISIBLE (-3325 4025);
FORCEPROP 1 LAST HDL_TAP TRUE
J 0
(-3000 3850);
DISPLAY 0.872340 (-3000 3850);
DISPLAY INVISIBLE (-3000 3850);
FORCEPROP 1 LAST PATH I200
J 0
(-3327 3975);
DISPLAY 0.872340 (-3327 3975);
PAINT GREEN (-3327 3975);
DISPLAY INVISIBLE (-3327 3975);
FORCEADD TAP..1
(-3325 3925);
FORCEPROP 3 LASTPIN (-3375 3925) SIG_NAME M_D_CPU1_SB_DQ<6>
J 0
(-3365 3935);
DISPLAY 0.659574 (-3365 3935);
PAINT MONO (-3365 3935);
DISPLAY INVISIBLE (-3365 3935);
FORCEPROP 1 LASTPIN (-3375 3925) BN 6
J 0
(-3387 3933);
DISPLAY 0.489362 (-3387 3933);
PAINT GREEN (-3387 3933);
FORCEPROP 2 LAST CDS_LIB mstr_standard
J 0
(-3325 3925);
DISPLAY 0.723404 (-3325 3925);
PAINT MONO (-3325 3925);
DISPLAY INVISIBLE (-3325 3925);
FORCEPROP 1 LAST BODY_TYPE PLUMBING
J 0
(-3325 3975);
DISPLAY 0.872340 (-3325 3975);
PAINT GREEN (-3325 3975);
DISPLAY INVISIBLE (-3325 3975);
FORCEPROP 1 LAST HDL_TAP TRUE
J 0
(-3000 3800);
DISPLAY 0.872340 (-3000 3800);
DISPLAY INVISIBLE (-3000 3800);
FORCEPROP 1 LAST PATH I201
J 0
(-3327 3925);
DISPLAY 0.872340 (-3327 3925);
PAINT GREEN (-3327 3925);
DISPLAY INVISIBLE (-3327 3925);
FORCEADD TAP..1
(-3325 3875);
FORCEPROP 3 LASTPIN (-3375 3875) SIG_NAME M_D_CPU1_SB_DQ<7>
J 0
(-3365 3885);
DISPLAY 0.659574 (-3365 3885);
PAINT MONO (-3365 3885);
DISPLAY INVISIBLE (-3365 3885);
FORCEPROP 1 LASTPIN (-3375 3875) BN 7
J 0
(-3387 3883);
DISPLAY 0.489362 (-3387 3883);
PAINT GREEN (-3387 3883);
FORCEPROP 2 LAST CDS_LIB mstr_standard
J 0
(-3325 3875);
DISPLAY 0.723404 (-3325 3875);
PAINT MONO (-3325 3875);
DISPLAY INVISIBLE (-3325 3875);
FORCEPROP 1 LAST BODY_TYPE PLUMBING
J 0
(-3325 3925);
DISPLAY 0.872340 (-3325 3925);
PAINT GREEN (-3325 3925);
DISPLAY INVISIBLE (-3325 3925);
FORCEPROP 1 LAST HDL_TAP TRUE
J 0
(-3000 3750);
DISPLAY 0.872340 (-3000 3750);
DISPLAY INVISIBLE (-3000 3750);
FORCEPROP 1 LAST PATH I202
J 0
(-3327 3875);
DISPLAY 0.872340 (-3327 3875);
PAINT GREEN (-3327 3875);
DISPLAY INVISIBLE (-3327 3875);
FORCEADD TAP..1
(-3325 3625);
FORCEPROP 3 LASTPIN (-3375 3625) SIG_NAME M_D_CPU1_SB_DQ<11>
J 0
(-3365 3635);
DISPLAY 0.659574 (-3365 3635);
PAINT MONO (-3365 3635);
DISPLAY INVISIBLE (-3365 3635);
FORCEPROP 1 LASTPIN (-3375 3625) BN 11
J 0
(-3387 3633);
DISPLAY 0.489362 (-3387 3633);
PAINT GREEN (-3387 3633);
FORCEPROP 2 LAST CDS_LIB mstr_standard
J 0
(-3325 3625);
DISPLAY 0.723404 (-3325 3625);
PAINT MONO (-3325 3625);
DISPLAY INVISIBLE (-3325 3625);
FORCEPROP 1 LAST BODY_TYPE PLUMBING
J 0
(-3325 3675);
DISPLAY 0.872340 (-3325 3675);
PAINT GREEN (-3325 3675);
DISPLAY INVISIBLE (-3325 3675);
FORCEPROP 1 LAST HDL_TAP TRUE
J 0
(-3000 3500);
DISPLAY 0.872340 (-3000 3500);
DISPLAY INVISIBLE (-3000 3500);
FORCEPROP 1 LAST PATH I203
J 0
(-3327 3625);
DISPLAY 0.872340 (-3327 3625);
PAINT GREEN (-3327 3625);
DISPLAY INVISIBLE (-3327 3625);
FORCEADD TAP..1
(-3325 3675);
FORCEPROP 3 LASTPIN (-3375 3675) SIG_NAME M_D_CPU1_SB_DQ<10>
J 0
(-3365 3685);
DISPLAY 0.659574 (-3365 3685);
PAINT MONO (-3365 3685);
DISPLAY INVISIBLE (-3365 3685);
FORCEPROP 1 LASTPIN (-3375 3675) BN 10
J 0
(-3387 3683);
DISPLAY 0.489362 (-3387 3683);
PAINT GREEN (-3387 3683);
FORCEPROP 2 LAST CDS_LIB mstr_standard
J 0
(-3325 3675);
DISPLAY 0.723404 (-3325 3675);
PAINT MONO (-3325 3675);
DISPLAY INVISIBLE (-3325 3675);
FORCEPROP 1 LAST BODY_TYPE PLUMBING
J 0
(-3325 3725);
DISPLAY 0.872340 (-3325 3725);
PAINT GREEN (-3325 3725);
DISPLAY INVISIBLE (-3325 3725);
FORCEPROP 1 LAST HDL_TAP TRUE
J 0
(-3000 3550);
DISPLAY 0.872340 (-3000 3550);
DISPLAY INVISIBLE (-3000 3550);
FORCEPROP 1 LAST PATH I204
J 0
(-3327 3675);
DISPLAY 0.872340 (-3327 3675);
PAINT GREEN (-3327 3675);
DISPLAY INVISIBLE (-3327 3675);
FORCEADD TAP..1
(-3325 3775);
FORCEPROP 3 LASTPIN (-3375 3775) SIG_NAME M_D_CPU1_SB_DQ<8>
J 0
(-3365 3785);
DISPLAY 0.659574 (-3365 3785);
PAINT MONO (-3365 3785);
DISPLAY INVISIBLE (-3365 3785);
FORCEPROP 1 LASTPIN (-3375 3775) BN 8
J 0
(-3387 3783);
DISPLAY 0.489362 (-3387 3783);
PAINT GREEN (-3387 3783);
FORCEPROP 2 LAST CDS_LIB mstr_standard
J 0
(-3325 3775);
DISPLAY 0.723404 (-3325 3775);
PAINT MONO (-3325 3775);
DISPLAY INVISIBLE (-3325 3775);
FORCEPROP 1 LAST BODY_TYPE PLUMBING
J 0
(-3325 3825);
DISPLAY 0.872340 (-3325 3825);
PAINT GREEN (-3325 3825);
DISPLAY INVISIBLE (-3325 3825);
FORCEPROP 1 LAST HDL_TAP TRUE
J 0
(-3000 3650);
DISPLAY 0.872340 (-3000 3650);
DISPLAY INVISIBLE (-3000 3650);
FORCEPROP 1 LAST PATH I205
J 0
(-3327 3775);
DISPLAY 0.872340 (-3327 3775);
PAINT GREEN (-3327 3775);
DISPLAY INVISIBLE (-3327 3775);
FORCEADD TAP..1
(-3325 3725);
FORCEPROP 3 LASTPIN (-3375 3725) SIG_NAME M_D_CPU1_SB_DQ<9>
J 0
(-3365 3735);
DISPLAY 0.659574 (-3365 3735);
PAINT MONO (-3365 3735);
DISPLAY INVISIBLE (-3365 3735);
FORCEPROP 1 LASTPIN (-3375 3725) BN 9
J 0
(-3387 3733);
DISPLAY 0.489362 (-3387 3733);
PAINT GREEN (-3387 3733);
FORCEPROP 2 LAST CDS_LIB mstr_standard
J 0
(-3325 3725);
DISPLAY 0.723404 (-3325 3725);
PAINT MONO (-3325 3725);
DISPLAY INVISIBLE (-3325 3725);
FORCEPROP 1 LAST BODY_TYPE PLUMBING
J 0
(-3325 3775);
DISPLAY 0.872340 (-3325 3775);
PAINT GREEN (-3325 3775);
DISPLAY INVISIBLE (-3325 3775);
FORCEPROP 1 LAST HDL_TAP TRUE
J 0
(-3000 3600);
DISPLAY 0.872340 (-3000 3600);
DISPLAY INVISIBLE (-3000 3600);
FORCEPROP 1 LAST PATH I206
J 0
(-3327 3725);
DISPLAY 0.872340 (-3327 3725);
PAINT GREEN (-3327 3725);
DISPLAY INVISIBLE (-3327 3725);
FORCEADD TAP..1
(-3325 3425);
FORCEPROP 3 LASTPIN (-3375 3425) SIG_NAME M_D_CPU1_SB_DQ<15>
J 0
(-3365 3435);
DISPLAY 0.659574 (-3365 3435);
PAINT MONO (-3365 3435);
DISPLAY INVISIBLE (-3365 3435);
FORCEPROP 1 LASTPIN (-3375 3425) BN 15
J 0
(-3387 3433);
DISPLAY 0.489362 (-3387 3433);
PAINT GREEN (-3387 3433);
FORCEPROP 2 LAST CDS_LIB mstr_standard
J 0
(-3325 3425);
DISPLAY 0.723404 (-3325 3425);
PAINT MONO (-3325 3425);
DISPLAY INVISIBLE (-3325 3425);
FORCEPROP 1 LAST BODY_TYPE PLUMBING
J 0
(-3325 3475);
DISPLAY 0.872340 (-3325 3475);
PAINT GREEN (-3325 3475);
DISPLAY INVISIBLE (-3325 3475);
FORCEPROP 1 LAST HDL_TAP TRUE
J 0
(-3000 3300);
DISPLAY 0.872340 (-3000 3300);
DISPLAY INVISIBLE (-3000 3300);
FORCEPROP 1 LAST PATH I207
J 0
(-3327 3425);
DISPLAY 0.872340 (-3327 3425);
PAINT GREEN (-3327 3425);
DISPLAY INVISIBLE (-3327 3425);
FORCEADD TAP..1
(-3325 3475);
FORCEPROP 3 LASTPIN (-3375 3475) SIG_NAME M_D_CPU1_SB_DQ<14>
J 0
(-3365 3485);
DISPLAY 0.659574 (-3365 3485);
PAINT MONO (-3365 3485);
DISPLAY INVISIBLE (-3365 3485);
FORCEPROP 1 LASTPIN (-3375 3475) BN 14
J 0
(-3387 3483);
DISPLAY 0.489362 (-3387 3483);
PAINT GREEN (-3387 3483);
FORCEPROP 2 LAST CDS_LIB mstr_standard
J 0
(-3325 3475);
DISPLAY 0.723404 (-3325 3475);
PAINT MONO (-3325 3475);
DISPLAY INVISIBLE (-3325 3475);
FORCEPROP 1 LAST BODY_TYPE PLUMBING
J 0
(-3325 3525);
DISPLAY 0.872340 (-3325 3525);
PAINT GREEN (-3325 3525);
DISPLAY INVISIBLE (-3325 3525);
FORCEPROP 1 LAST HDL_TAP TRUE
J 0
(-3000 3350);
DISPLAY 0.872340 (-3000 3350);
DISPLAY INVISIBLE (-3000 3350);
FORCEPROP 1 LAST PATH I208
J 0
(-3327 3475);
DISPLAY 0.872340 (-3327 3475);
PAINT GREEN (-3327 3475);
DISPLAY INVISIBLE (-3327 3475);
FORCEADD TAP..1
(-3325 3575);
FORCEPROP 3 LASTPIN (-3375 3575) SIG_NAME M_D_CPU1_SB_DQ<12>
J 0
(-3365 3585);
DISPLAY 0.659574 (-3365 3585);
PAINT MONO (-3365 3585);
DISPLAY INVISIBLE (-3365 3585);
FORCEPROP 1 LASTPIN (-3375 3575) BN 12
J 0
(-3387 3583);
DISPLAY 0.489362 (-3387 3583);
PAINT GREEN (-3387 3583);
FORCEPROP 2 LAST CDS_LIB mstr_standard
J 0
(-3325 3575);
DISPLAY 0.723404 (-3325 3575);
PAINT MONO (-3325 3575);
DISPLAY INVISIBLE (-3325 3575);
FORCEPROP 1 LAST BODY_TYPE PLUMBING
J 0
(-3325 3625);
DISPLAY 0.872340 (-3325 3625);
PAINT GREEN (-3325 3625);
DISPLAY INVISIBLE (-3325 3625);
FORCEPROP 1 LAST HDL_TAP TRUE
J 0
(-3000 3450);
DISPLAY 0.872340 (-3000 3450);
DISPLAY INVISIBLE (-3000 3450);
FORCEPROP 1 LAST PATH I209
J 0
(-3327 3575);
DISPLAY 0.872340 (-3327 3575);
PAINT GREEN (-3327 3575);
DISPLAY INVISIBLE (-3327 3575);
FORCEADD TAP..1
(-3325 3525);
FORCEPROP 3 LASTPIN (-3375 3525) SIG_NAME M_D_CPU1_SB_DQ<13>
J 0
(-3365 3535);
DISPLAY 0.659574 (-3365 3535);
PAINT MONO (-3365 3535);
DISPLAY INVISIBLE (-3365 3535);
FORCEPROP 1 LASTPIN (-3375 3525) BN 13
J 0
(-3387 3533);
DISPLAY 0.489362 (-3387 3533);
PAINT GREEN (-3387 3533);
FORCEPROP 2 LAST CDS_LIB mstr_standard
J 0
(-3325 3525);
DISPLAY 0.723404 (-3325 3525);
PAINT MONO (-3325 3525);
DISPLAY INVISIBLE (-3325 3525);
FORCEPROP 1 LAST BODY_TYPE PLUMBING
J 0
(-3325 3575);
DISPLAY 0.872340 (-3325 3575);
PAINT GREEN (-3325 3575);
DISPLAY INVISIBLE (-3325 3575);
FORCEPROP 1 LAST HDL_TAP TRUE
J 0
(-3000 3400);
DISPLAY 0.872340 (-3000 3400);
DISPLAY INVISIBLE (-3000 3400);
FORCEPROP 1 LAST PATH I210
J 0
(-3327 3525);
DISPLAY 0.872340 (-3327 3525);
PAINT GREEN (-3327 3525);
DISPLAY INVISIBLE (-3327 3525);
FORCEADD TAP..1
(-3325 3325);
FORCEPROP 3 LASTPIN (-3375 3325) SIG_NAME M_D_CPU1_SB_DQ<16>
J 0
(-3365 3335);
DISPLAY 0.659574 (-3365 3335);
PAINT MONO (-3365 3335);
DISPLAY INVISIBLE (-3365 3335);
FORCEPROP 1 LASTPIN (-3375 3325) BN 16
J 0
(-3387 3333);
DISPLAY 0.489362 (-3387 3333);
PAINT GREEN (-3387 3333);
FORCEPROP 2 LAST CDS_LIB mstr_standard
J 0
(-3325 3325);
DISPLAY 0.723404 (-3325 3325);
PAINT MONO (-3325 3325);
DISPLAY INVISIBLE (-3325 3325);
FORCEPROP 1 LAST BODY_TYPE PLUMBING
J 0
(-3325 3375);
DISPLAY 0.872340 (-3325 3375);
PAINT GREEN (-3325 3375);
DISPLAY INVISIBLE (-3325 3375);
FORCEPROP 1 LAST HDL_TAP TRUE
J 0
(-3000 3200);
DISPLAY 0.872340 (-3000 3200);
DISPLAY INVISIBLE (-3000 3200);
FORCEPROP 1 LAST PATH I211
J 0
(-3327 3325);
DISPLAY 0.872340 (-3327 3325);
PAINT GREEN (-3327 3325);
DISPLAY INVISIBLE (-3327 3325);
FORCEADD TAP..1
(-3325 3275);
FORCEPROP 3 LASTPIN (-3375 3275) SIG_NAME M_D_CPU1_SB_DQ<17>
J 0
(-3365 3285);
DISPLAY 0.659574 (-3365 3285);
PAINT MONO (-3365 3285);
DISPLAY INVISIBLE (-3365 3285);
FORCEPROP 1 LASTPIN (-3375 3275) BN 17
J 0
(-3387 3283);
DISPLAY 0.489362 (-3387 3283);
PAINT GREEN (-3387 3283);
FORCEPROP 2 LAST CDS_LIB mstr_standard
J 0
(-3325 3275);
DISPLAY 0.723404 (-3325 3275);
PAINT MONO (-3325 3275);
DISPLAY INVISIBLE (-3325 3275);
FORCEPROP 1 LAST BODY_TYPE PLUMBING
J 0
(-3325 3325);
DISPLAY 0.872340 (-3325 3325);
PAINT GREEN (-3325 3325);
DISPLAY INVISIBLE (-3325 3325);
FORCEPROP 1 LAST HDL_TAP TRUE
J 0
(-3000 3150);
DISPLAY 0.872340 (-3000 3150);
DISPLAY INVISIBLE (-3000 3150);
FORCEPROP 1 LAST PATH I212
J 0
(-3327 3275);
DISPLAY 0.872340 (-3327 3275);
PAINT GREEN (-3327 3275);
DISPLAY INVISIBLE (-3327 3275);
FORCEADD TAP..1
(-3325 3225);
FORCEPROP 3 LASTPIN (-3375 3225) SIG_NAME M_D_CPU1_SB_DQ<18>
J 0
(-3365 3235);
DISPLAY 0.659574 (-3365 3235);
PAINT MONO (-3365 3235);
DISPLAY INVISIBLE (-3365 3235);
FORCEPROP 1 LASTPIN (-3375 3225) BN 18
J 0
(-3387 3233);
DISPLAY 0.489362 (-3387 3233);
PAINT GREEN (-3387 3233);
FORCEPROP 2 LAST CDS_LIB mstr_standard
J 0
(-3325 3225);
DISPLAY 0.723404 (-3325 3225);
PAINT MONO (-3325 3225);
DISPLAY INVISIBLE (-3325 3225);
FORCEPROP 1 LAST BODY_TYPE PLUMBING
J 0
(-3325 3275);
DISPLAY 0.872340 (-3325 3275);
PAINT GREEN (-3325 3275);
DISPLAY INVISIBLE (-3325 3275);
FORCEPROP 1 LAST HDL_TAP TRUE
J 0
(-3000 3100);
DISPLAY 0.872340 (-3000 3100);
DISPLAY INVISIBLE (-3000 3100);
FORCEPROP 1 LAST PATH I213
J 0
(-3327 3225);
DISPLAY 0.872340 (-3327 3225);
PAINT GREEN (-3327 3225);
DISPLAY INVISIBLE (-3327 3225);
FORCEADD TAP..1
(-3325 3075);
FORCEPROP 3 LASTPIN (-3375 3075) SIG_NAME M_D_CPU1_SB_DQ<21>
J 0
(-3365 3085);
DISPLAY 0.659574 (-3365 3085);
PAINT MONO (-3365 3085);
DISPLAY INVISIBLE (-3365 3085);
FORCEPROP 1 LASTPIN (-3375 3075) BN 21
J 0
(-3387 3083);
DISPLAY 0.489362 (-3387 3083);
PAINT GREEN (-3387 3083);
FORCEPROP 2 LAST CDS_LIB mstr_standard
J 0
(-3325 3075);
DISPLAY 0.723404 (-3325 3075);
PAINT MONO (-3325 3075);
DISPLAY INVISIBLE (-3325 3075);
FORCEPROP 1 LAST BODY_TYPE PLUMBING
J 0
(-3325 3125);
DISPLAY 0.872340 (-3325 3125);
PAINT GREEN (-3325 3125);
DISPLAY INVISIBLE (-3325 3125);
FORCEPROP 1 LAST HDL_TAP TRUE
J 0
(-3000 2950);
DISPLAY 0.872340 (-3000 2950);
DISPLAY INVISIBLE (-3000 2950);
FORCEPROP 1 LAST PATH I214
J 0
(-3327 3075);
DISPLAY 0.872340 (-3327 3075);
PAINT GREEN (-3327 3075);
DISPLAY INVISIBLE (-3327 3075);
FORCEADD TAP..1
(-3325 3175);
FORCEPROP 3 LASTPIN (-3375 3175) SIG_NAME M_D_CPU1_SB_DQ<19>
J 0
(-3365 3185);
DISPLAY 0.659574 (-3365 3185);
PAINT MONO (-3365 3185);
DISPLAY INVISIBLE (-3365 3185);
FORCEPROP 1 LASTPIN (-3375 3175) BN 19
J 0
(-3387 3183);
DISPLAY 0.489362 (-3387 3183);
PAINT GREEN (-3387 3183);
FORCEPROP 2 LAST CDS_LIB mstr_standard
J 0
(-3325 3175);
DISPLAY 0.723404 (-3325 3175);
PAINT MONO (-3325 3175);
DISPLAY INVISIBLE (-3325 3175);
FORCEPROP 1 LAST BODY_TYPE PLUMBING
J 0
(-3325 3225);
DISPLAY 0.872340 (-3325 3225);
PAINT GREEN (-3325 3225);
DISPLAY INVISIBLE (-3325 3225);
FORCEPROP 1 LAST HDL_TAP TRUE
J 0
(-3000 3050);
DISPLAY 0.872340 (-3000 3050);
DISPLAY INVISIBLE (-3000 3050);
FORCEPROP 1 LAST PATH I215
J 0
(-3327 3175);
DISPLAY 0.872340 (-3327 3175);
PAINT GREEN (-3327 3175);
DISPLAY INVISIBLE (-3327 3175);
FORCEADD TAP..1
(-3325 3125);
FORCEPROP 3 LASTPIN (-3375 3125) SIG_NAME M_D_CPU1_SB_DQ<20>
J 0
(-3365 3135);
DISPLAY 0.659574 (-3365 3135);
PAINT MONO (-3365 3135);
DISPLAY INVISIBLE (-3365 3135);
FORCEPROP 1 LASTPIN (-3375 3125) BN 20
J 0
(-3387 3133);
DISPLAY 0.489362 (-3387 3133);
PAINT GREEN (-3387 3133);
FORCEPROP 2 LAST CDS_LIB mstr_standard
J 0
(-3325 3125);
DISPLAY 0.723404 (-3325 3125);
PAINT MONO (-3325 3125);
DISPLAY INVISIBLE (-3325 3125);
FORCEPROP 1 LAST BODY_TYPE PLUMBING
J 0
(-3325 3175);
DISPLAY 0.872340 (-3325 3175);
PAINT GREEN (-3325 3175);
DISPLAY INVISIBLE (-3325 3175);
FORCEPROP 1 LAST HDL_TAP TRUE
J 0
(-3000 3000);
DISPLAY 0.872340 (-3000 3000);
DISPLAY INVISIBLE (-3000 3000);
FORCEPROP 1 LAST PATH I216
J 0
(-3327 3125);
DISPLAY 0.872340 (-3327 3125);
PAINT GREEN (-3327 3125);
DISPLAY INVISIBLE (-3327 3125);
FORCEADD TAP..1
(-3325 2875);
FORCEPROP 3 LASTPIN (-3375 2875) SIG_NAME M_D_CPU1_SB_DQ<24>
J 0
(-3365 2885);
DISPLAY 0.659574 (-3365 2885);
PAINT MONO (-3365 2885);
DISPLAY INVISIBLE (-3365 2885);
FORCEPROP 1 LASTPIN (-3375 2875) BN 24
J 0
(-3387 2883);
DISPLAY 0.489362 (-3387 2883);
PAINT GREEN (-3387 2883);
FORCEPROP 2 LAST CDS_LIB mstr_standard
J 0
(-3325 2875);
DISPLAY 0.723404 (-3325 2875);
PAINT MONO (-3325 2875);
DISPLAY INVISIBLE (-3325 2875);
FORCEPROP 1 LAST BODY_TYPE PLUMBING
J 0
(-3325 2925);
DISPLAY 0.872340 (-3325 2925);
PAINT GREEN (-3325 2925);
DISPLAY INVISIBLE (-3325 2925);
FORCEPROP 1 LAST HDL_TAP TRUE
J 0
(-3000 2750);
DISPLAY 0.872340 (-3000 2750);
DISPLAY INVISIBLE (-3000 2750);
FORCEPROP 1 LAST PATH I217
J 0
(-3327 2875);
DISPLAY 0.872340 (-3327 2875);
PAINT GREEN (-3327 2875);
DISPLAY INVISIBLE (-3327 2875);
FORCEADD TAP..1
(-3325 2975);
FORCEPROP 3 LASTPIN (-3375 2975) SIG_NAME M_D_CPU1_SB_DQ<23>
J 0
(-3365 2985);
DISPLAY 0.659574 (-3365 2985);
PAINT MONO (-3365 2985);
DISPLAY INVISIBLE (-3365 2985);
FORCEPROP 1 LASTPIN (-3375 2975) BN 23
J 0
(-3387 2983);
DISPLAY 0.489362 (-3387 2983);
PAINT GREEN (-3387 2983);
FORCEPROP 2 LAST CDS_LIB mstr_standard
J 0
(-3325 2975);
DISPLAY 0.723404 (-3325 2975);
PAINT MONO (-3325 2975);
DISPLAY INVISIBLE (-3325 2975);
FORCEPROP 1 LAST BODY_TYPE PLUMBING
J 0
(-3325 3025);
DISPLAY 0.872340 (-3325 3025);
PAINT GREEN (-3325 3025);
DISPLAY INVISIBLE (-3325 3025);
FORCEPROP 1 LAST HDL_TAP TRUE
J 0
(-3000 2850);
DISPLAY 0.872340 (-3000 2850);
DISPLAY INVISIBLE (-3000 2850);
FORCEPROP 1 LAST PATH I218
J 0
(-3327 2975);
DISPLAY 0.872340 (-3327 2975);
PAINT GREEN (-3327 2975);
DISPLAY INVISIBLE (-3327 2975);
FORCEADD TAP..1
(-3325 3025);
FORCEPROP 3 LASTPIN (-3375 3025) SIG_NAME M_D_CPU1_SB_DQ<22>
J 0
(-3365 3035);
DISPLAY 0.659574 (-3365 3035);
PAINT MONO (-3365 3035);
DISPLAY INVISIBLE (-3365 3035);
FORCEPROP 1 LASTPIN (-3375 3025) BN 22
J 0
(-3387 3033);
DISPLAY 0.489362 (-3387 3033);
PAINT GREEN (-3387 3033);
FORCEPROP 2 LAST CDS_LIB mstr_standard
J 0
(-3325 3025);
DISPLAY 0.723404 (-3325 3025);
PAINT MONO (-3325 3025);
DISPLAY INVISIBLE (-3325 3025);
FORCEPROP 1 LAST BODY_TYPE PLUMBING
J 0
(-3325 3075);
DISPLAY 0.872340 (-3325 3075);
PAINT GREEN (-3325 3075);
DISPLAY INVISIBLE (-3325 3075);
FORCEPROP 1 LAST HDL_TAP TRUE
J 0
(-3000 2900);
DISPLAY 0.872340 (-3000 2900);
DISPLAY INVISIBLE (-3000 2900);
FORCEPROP 1 LAST PATH I219
J 0
(-3327 3025);
DISPLAY 0.872340 (-3327 3025);
PAINT GREEN (-3327 3025);
DISPLAY INVISIBLE (-3327 3025);
FORCEADD TAP..1
(-3325 2825);
FORCEPROP 3 LASTPIN (-3375 2825) SIG_NAME M_D_CPU1_SB_DQ<25>
J 0
(-3365 2835);
DISPLAY 0.659574 (-3365 2835);
PAINT MONO (-3365 2835);
DISPLAY INVISIBLE (-3365 2835);
FORCEPROP 1 LASTPIN (-3375 2825) BN 25
J 0
(-3387 2833);
DISPLAY 0.489362 (-3387 2833);
PAINT GREEN (-3387 2833);
FORCEPROP 2 LAST CDS_LIB mstr_standard
J 0
(-3325 2825);
DISPLAY 0.723404 (-3325 2825);
PAINT MONO (-3325 2825);
DISPLAY INVISIBLE (-3325 2825);
FORCEPROP 1 LAST BODY_TYPE PLUMBING
J 0
(-3325 2875);
DISPLAY 0.872340 (-3325 2875);
PAINT GREEN (-3325 2875);
DISPLAY INVISIBLE (-3325 2875);
FORCEPROP 1 LAST HDL_TAP TRUE
J 0
(-3000 2700);
DISPLAY 0.872340 (-3000 2700);
DISPLAY INVISIBLE (-3000 2700);
FORCEPROP 1 LAST PATH I220
J 0
(-3327 2825);
DISPLAY 0.872340 (-3327 2825);
PAINT GREEN (-3327 2825);
DISPLAY INVISIBLE (-3327 2825);
FORCEADD TAP..1
(-3325 2625);
FORCEPROP 3 LASTPIN (-3375 2625) SIG_NAME M_D_CPU1_SB_DQ<29>
J 0
(-3365 2635);
DISPLAY 0.659574 (-3365 2635);
PAINT MONO (-3365 2635);
DISPLAY INVISIBLE (-3365 2635);
FORCEPROP 1 LASTPIN (-3375 2625) BN 29
J 0
(-3387 2633);
DISPLAY 0.489362 (-3387 2633);
PAINT GREEN (-3387 2633);
FORCEPROP 2 LAST CDS_LIB mstr_standard
J 0
(-3325 2625);
DISPLAY 0.723404 (-3325 2625);
PAINT MONO (-3325 2625);
DISPLAY INVISIBLE (-3325 2625);
FORCEPROP 1 LAST BODY_TYPE PLUMBING
J 0
(-3325 2675);
DISPLAY 0.872340 (-3325 2675);
PAINT GREEN (-3325 2675);
DISPLAY INVISIBLE (-3325 2675);
FORCEPROP 1 LAST HDL_TAP TRUE
J 0
(-3000 2500);
DISPLAY 0.872340 (-3000 2500);
DISPLAY INVISIBLE (-3000 2500);
FORCEPROP 1 LAST PATH I221
J 0
(-3327 2625);
DISPLAY 0.872340 (-3327 2625);
PAINT GREEN (-3327 2625);
DISPLAY INVISIBLE (-3327 2625);
FORCEADD TAP..1
(-3325 2575);
FORCEPROP 3 LASTPIN (-3375 2575) SIG_NAME M_D_CPU1_SB_DQ<30>
J 0
(-3365 2585);
DISPLAY 0.659574 (-3365 2585);
PAINT MONO (-3365 2585);
DISPLAY INVISIBLE (-3365 2585);
FORCEPROP 1 LASTPIN (-3375 2575) BN 30
J 0
(-3387 2583);
DISPLAY 0.489362 (-3387 2583);
PAINT GREEN (-3387 2583);
FORCEPROP 2 LAST CDS_LIB mstr_standard
J 0
(-3325 2575);
DISPLAY 0.723404 (-3325 2575);
PAINT MONO (-3325 2575);
DISPLAY INVISIBLE (-3325 2575);
FORCEPROP 1 LAST BODY_TYPE PLUMBING
J 0
(-3325 2625);
DISPLAY 0.872340 (-3325 2625);
PAINT GREEN (-3325 2625);
DISPLAY INVISIBLE (-3325 2625);
FORCEPROP 1 LAST HDL_TAP TRUE
J 0
(-3000 2450);
DISPLAY 0.872340 (-3000 2450);
DISPLAY INVISIBLE (-3000 2450);
FORCEPROP 1 LAST PATH I222
J 0
(-3327 2575);
DISPLAY 0.872340 (-3327 2575);
PAINT GREEN (-3327 2575);
DISPLAY INVISIBLE (-3327 2575);
FORCEADD TAP..1
(-3325 2675);
FORCEPROP 3 LASTPIN (-3375 2675) SIG_NAME M_D_CPU1_SB_DQ<28>
J 0
(-3365 2685);
DISPLAY 0.659574 (-3365 2685);
PAINT MONO (-3365 2685);
DISPLAY INVISIBLE (-3365 2685);
FORCEPROP 1 LASTPIN (-3375 2675) BN 28
J 0
(-3387 2683);
DISPLAY 0.489362 (-3387 2683);
PAINT GREEN (-3387 2683);
FORCEPROP 2 LAST CDS_LIB mstr_standard
J 0
(-3325 2675);
DISPLAY 0.723404 (-3325 2675);
PAINT MONO (-3325 2675);
DISPLAY INVISIBLE (-3325 2675);
FORCEPROP 1 LAST BODY_TYPE PLUMBING
J 0
(-3325 2725);
DISPLAY 0.872340 (-3325 2725);
PAINT GREEN (-3325 2725);
DISPLAY INVISIBLE (-3325 2725);
FORCEPROP 1 LAST HDL_TAP TRUE
J 0
(-3000 2550);
DISPLAY 0.872340 (-3000 2550);
DISPLAY INVISIBLE (-3000 2550);
FORCEPROP 1 LAST PATH I223
J 0
(-3327 2675);
DISPLAY 0.872340 (-3327 2675);
PAINT GREEN (-3327 2675);
DISPLAY INVISIBLE (-3327 2675);
FORCEADD TAP..1
(-3325 2775);
FORCEPROP 3 LASTPIN (-3375 2775) SIG_NAME M_D_CPU1_SB_DQ<26>
J 0
(-3365 2785);
DISPLAY 0.659574 (-3365 2785);
PAINT MONO (-3365 2785);
DISPLAY INVISIBLE (-3365 2785);
FORCEPROP 1 LASTPIN (-3375 2775) BN 26
J 0
(-3387 2783);
DISPLAY 0.489362 (-3387 2783);
PAINT GREEN (-3387 2783);
FORCEPROP 2 LAST CDS_LIB mstr_standard
J 0
(-3325 2775);
DISPLAY 0.723404 (-3325 2775);
PAINT MONO (-3325 2775);
DISPLAY INVISIBLE (-3325 2775);
FORCEPROP 1 LAST BODY_TYPE PLUMBING
J 0
(-3325 2825);
DISPLAY 0.872340 (-3325 2825);
PAINT GREEN (-3325 2825);
DISPLAY INVISIBLE (-3325 2825);
FORCEPROP 1 LAST HDL_TAP TRUE
J 0
(-3000 2650);
DISPLAY 0.872340 (-3000 2650);
DISPLAY INVISIBLE (-3000 2650);
FORCEPROP 1 LAST PATH I224
J 0
(-3327 2775);
DISPLAY 0.872340 (-3327 2775);
PAINT GREEN (-3327 2775);
DISPLAY INVISIBLE (-3327 2775);
FORCEADD TAP..1
(-3325 2725);
FORCEPROP 3 LASTPIN (-3375 2725) SIG_NAME M_D_CPU1_SB_DQ<27>
J 0
(-3365 2735);
DISPLAY 0.659574 (-3365 2735);
PAINT MONO (-3365 2735);
DISPLAY INVISIBLE (-3365 2735);
FORCEPROP 1 LASTPIN (-3375 2725) BN 27
J 0
(-3387 2733);
DISPLAY 0.489362 (-3387 2733);
PAINT GREEN (-3387 2733);
FORCEPROP 2 LAST CDS_LIB mstr_standard
J 0
(-3325 2725);
DISPLAY 0.723404 (-3325 2725);
PAINT MONO (-3325 2725);
DISPLAY INVISIBLE (-3325 2725);
FORCEPROP 1 LAST BODY_TYPE PLUMBING
J 0
(-3325 2775);
DISPLAY 0.872340 (-3325 2775);
PAINT GREEN (-3325 2775);
DISPLAY INVISIBLE (-3325 2775);
FORCEPROP 1 LAST HDL_TAP TRUE
J 0
(-3000 2600);
DISPLAY 0.872340 (-3000 2600);
DISPLAY INVISIBLE (-3000 2600);
FORCEPROP 1 LAST PATH I225
J 0
(-3327 2725);
DISPLAY 0.872340 (-3327 2725);
PAINT GREEN (-3327 2725);
DISPLAY INVISIBLE (-3327 2725);
FORCEADD TAP..1
(-3325 2525);
FORCEPROP 3 LASTPIN (-3375 2525) SIG_NAME M_D_CPU1_SB_DQ<31>
J 0
(-3365 2535);
DISPLAY 0.659574 (-3365 2535);
PAINT MONO (-3365 2535);
DISPLAY INVISIBLE (-3365 2535);
FORCEPROP 1 LASTPIN (-3375 2525) BN 31
J 0
(-3387 2533);
DISPLAY 0.489362 (-3387 2533);
PAINT GREEN (-3387 2533);
FORCEPROP 2 LAST CDS_LIB mstr_standard
J 0
(-3325 2525);
DISPLAY 0.723404 (-3325 2525);
PAINT MONO (-3325 2525);
DISPLAY INVISIBLE (-3325 2525);
FORCEPROP 1 LAST BODY_TYPE PLUMBING
J 0
(-3325 2575);
DISPLAY 0.872340 (-3325 2575);
PAINT GREEN (-3325 2575);
DISPLAY INVISIBLE (-3325 2575);
FORCEPROP 1 LAST HDL_TAP TRUE
J 0
(-3000 2400);
DISPLAY 0.872340 (-3000 2400);
DISPLAY INVISIBLE (-3000 2400);
FORCEPROP 1 LAST PATH I226
J 0
(-3327 2525);
DISPLAY 0.872340 (-3327 2525);
PAINT GREEN (-3327 2525);
DISPLAY INVISIBLE (-3327 2525);
FORCEADD TAP..1
(-3325 2425);
FORCEPROP 3 LASTPIN (-3375 2425) SIG_NAME M_D_CPU1_SA_CB<0>
J 0
(-3365 2435);
DISPLAY 0.659574 (-3365 2435);
PAINT MONO (-3365 2435);
DISPLAY INVISIBLE (-3365 2435);
FORCEPROP 1 LASTPIN (-3375 2425) BN 0
J 0
(-3387 2433);
DISPLAY 0.489362 (-3387 2433);
PAINT GREEN (-3387 2433);
FORCEPROP 2 LAST CDS_LIB mstr_standard
J 2
(-3325 2425);
DISPLAY 0.723404 (-3325 2425);
PAINT MONO (-3325 2425);
DISPLAY INVISIBLE (-3325 2425);
FORCEPROP 1 LAST BODY_TYPE PLUMBING
J 0
(-3325 2475);
DISPLAY 0.872340 (-3325 2475);
PAINT GREEN (-3325 2475);
DISPLAY INVISIBLE (-3325 2475);
FORCEPROP 1 LAST HDL_TAP TRUE
J 0
(-3000 2300);
DISPLAY 0.872340 (-3000 2300);
DISPLAY INVISIBLE (-3000 2300);
FORCEPROP 1 LAST PATH I227
J 0
(-3327 2425);
DISPLAY 0.872340 (-3327 2425);
PAINT GREEN (-3327 2425);
DISPLAY INVISIBLE (-3327 2425);
FORCEADD TAP..1
(-3325 2325);
FORCEPROP 3 LASTPIN (-3375 2325) SIG_NAME M_D_CPU1_SA_CB<2>
J 0
(-3365 2335);
DISPLAY 0.659574 (-3365 2335);
PAINT MONO (-3365 2335);
DISPLAY INVISIBLE (-3365 2335);
FORCEPROP 1 LASTPIN (-3375 2325) BN 2
J 0
(-3387 2333);
DISPLAY 0.489362 (-3387 2333);
PAINT GREEN (-3387 2333);
FORCEPROP 2 LAST CDS_LIB mstr_standard
J 2
(-3325 2325);
DISPLAY 0.723404 (-3325 2325);
PAINT MONO (-3325 2325);
DISPLAY INVISIBLE (-3325 2325);
FORCEPROP 1 LAST BODY_TYPE PLUMBING
J 0
(-3325 2375);
DISPLAY 0.872340 (-3325 2375);
PAINT GREEN (-3325 2375);
DISPLAY INVISIBLE (-3325 2375);
FORCEPROP 1 LAST HDL_TAP TRUE
J 0
(-3000 2200);
DISPLAY 0.872340 (-3000 2200);
DISPLAY INVISIBLE (-3000 2200);
FORCEPROP 1 LAST PATH I228
J 0
(-3327 2325);
DISPLAY 0.872340 (-3327 2325);
PAINT GREEN (-3327 2325);
DISPLAY INVISIBLE (-3327 2325);
FORCEADD TAP..1
(-3325 2375);
FORCEPROP 3 LASTPIN (-3375 2375) SIG_NAME M_D_CPU1_SA_CB<1>
J 0
(-3365 2385);
DISPLAY 0.659574 (-3365 2385);
PAINT MONO (-3365 2385);
DISPLAY INVISIBLE (-3365 2385);
FORCEPROP 1 LASTPIN (-3375 2375) BN 1
J 0
(-3387 2383);
DISPLAY 0.489362 (-3387 2383);
PAINT GREEN (-3387 2383);
FORCEPROP 2 LAST CDS_LIB mstr_standard
J 2
(-3325 2375);
DISPLAY 0.723404 (-3325 2375);
PAINT MONO (-3325 2375);
DISPLAY INVISIBLE (-3325 2375);
FORCEPROP 1 LAST BODY_TYPE PLUMBING
J 0
(-3325 2425);
DISPLAY 0.872340 (-3325 2425);
PAINT GREEN (-3325 2425);
DISPLAY INVISIBLE (-3325 2425);
FORCEPROP 1 LAST HDL_TAP TRUE
J 0
(-3000 2250);
DISPLAY 0.872340 (-3000 2250);
DISPLAY INVISIBLE (-3000 2250);
FORCEPROP 1 LAST PATH I229
J 0
(-3327 2375);
DISPLAY 0.872340 (-3327 2375);
PAINT GREEN (-3327 2375);
DISPLAY INVISIBLE (-3327 2375);
FORCEADD TAP..1
(-3325 2275);
FORCEPROP 3 LASTPIN (-3375 2275) SIG_NAME M_D_CPU1_SA_CB<3>
J 0
(-3365 2285);
DISPLAY 0.659574 (-3365 2285);
PAINT MONO (-3365 2285);
DISPLAY INVISIBLE (-3365 2285);
FORCEPROP 1 LASTPIN (-3375 2275) BN 3
J 0
(-3387 2283);
DISPLAY 0.489362 (-3387 2283);
PAINT GREEN (-3387 2283);
FORCEPROP 2 LAST CDS_LIB mstr_standard
J 2
(-3325 2275);
DISPLAY 0.723404 (-3325 2275);
PAINT MONO (-3325 2275);
DISPLAY INVISIBLE (-3325 2275);
FORCEPROP 1 LAST BODY_TYPE PLUMBING
J 0
(-3325 2325);
DISPLAY 0.872340 (-3325 2325);
PAINT GREEN (-3325 2325);
DISPLAY INVISIBLE (-3325 2325);
FORCEPROP 1 LAST HDL_TAP TRUE
J 0
(-3000 2150);
DISPLAY 0.872340 (-3000 2150);
DISPLAY INVISIBLE (-3000 2150);
FORCEPROP 1 LAST PATH I230
J 0
(-3327 2275);
DISPLAY 0.872340 (-3327 2275);
PAINT GREEN (-3327 2275);
DISPLAY INVISIBLE (-3327 2275);
FORCEADD TAP..1
(-3325 2225);
FORCEPROP 3 LASTPIN (-3375 2225) SIG_NAME M_D_CPU1_SA_CB<4>
J 0
(-3365 2235);
DISPLAY 0.659574 (-3365 2235);
PAINT MONO (-3365 2235);
DISPLAY INVISIBLE (-3365 2235);
FORCEPROP 1 LASTPIN (-3375 2225) BN 4
J 0
(-3387 2233);
DISPLAY 0.489362 (-3387 2233);
PAINT GREEN (-3387 2233);
FORCEPROP 2 LAST CDS_LIB mstr_standard
J 2
(-3325 2225);
DISPLAY 0.723404 (-3325 2225);
PAINT MONO (-3325 2225);
DISPLAY INVISIBLE (-3325 2225);
FORCEPROP 1 LAST BODY_TYPE PLUMBING
J 0
(-3325 2275);
DISPLAY 0.872340 (-3325 2275);
PAINT GREEN (-3325 2275);
DISPLAY INVISIBLE (-3325 2275);
FORCEPROP 1 LAST HDL_TAP TRUE
J 0
(-3000 2100);
DISPLAY 0.872340 (-3000 2100);
DISPLAY INVISIBLE (-3000 2100);
FORCEPROP 1 LAST PATH I231
J 0
(-3327 2225);
DISPLAY 0.872340 (-3327 2225);
PAINT GREEN (-3327 2225);
DISPLAY INVISIBLE (-3327 2225);
FORCEADD TAP..1
(-3325 2175);
FORCEPROP 3 LASTPIN (-3375 2175) SIG_NAME M_D_CPU1_SA_CB<5>
J 0
(-3365 2185);
DISPLAY 0.659574 (-3365 2185);
PAINT MONO (-3365 2185);
DISPLAY INVISIBLE (-3365 2185);
FORCEPROP 1 LASTPIN (-3375 2175) BN 5
J 0
(-3387 2183);
DISPLAY 0.489362 (-3387 2183);
PAINT GREEN (-3387 2183);
FORCEPROP 2 LAST CDS_LIB mstr_standard
J 2
(-3325 2175);
DISPLAY 0.723404 (-3325 2175);
PAINT MONO (-3325 2175);
DISPLAY INVISIBLE (-3325 2175);
FORCEPROP 1 LAST BODY_TYPE PLUMBING
J 0
(-3325 2225);
DISPLAY 0.872340 (-3325 2225);
PAINT GREEN (-3325 2225);
DISPLAY INVISIBLE (-3325 2225);
FORCEPROP 1 LAST HDL_TAP TRUE
J 0
(-3000 2050);
DISPLAY 0.872340 (-3000 2050);
DISPLAY INVISIBLE (-3000 2050);
FORCEPROP 1 LAST PATH I232
J 0
(-3327 2175);
DISPLAY 0.872340 (-3327 2175);
PAINT GREEN (-3327 2175);
DISPLAY INVISIBLE (-3327 2175);
FORCEADD TAP..1
(-3325 2125);
FORCEPROP 3 LASTPIN (-3375 2125) SIG_NAME M_D_CPU1_SA_CB<6>
J 0
(-3365 2135);
DISPLAY 0.659574 (-3365 2135);
PAINT MONO (-3365 2135);
DISPLAY INVISIBLE (-3365 2135);
FORCEPROP 1 LASTPIN (-3375 2125) BN 6
J 0
(-3387 2133);
DISPLAY 0.489362 (-3387 2133);
PAINT GREEN (-3387 2133);
FORCEPROP 2 LAST CDS_LIB mstr_standard
J 2
(-3325 2125);
DISPLAY 0.723404 (-3325 2125);
PAINT MONO (-3325 2125);
DISPLAY INVISIBLE (-3325 2125);
FORCEPROP 1 LAST BODY_TYPE PLUMBING
J 0
(-3325 2175);
DISPLAY 0.872340 (-3325 2175);
PAINT GREEN (-3325 2175);
DISPLAY INVISIBLE (-3325 2175);
FORCEPROP 1 LAST HDL_TAP TRUE
J 0
(-3000 2000);
DISPLAY 0.872340 (-3000 2000);
DISPLAY INVISIBLE (-3000 2000);
FORCEPROP 1 LAST PATH I233
J 0
(-3327 2125);
DISPLAY 0.872340 (-3327 2125);
PAINT GREEN (-3327 2125);
DISPLAY INVISIBLE (-3327 2125);
FORCEADD TAP..1
(-3325 2075);
FORCEPROP 3 LASTPIN (-3375 2075) SIG_NAME M_D_CPU1_SA_CB<7>
J 0
(-3365 2085);
DISPLAY 0.659574 (-3365 2085);
PAINT MONO (-3365 2085);
DISPLAY INVISIBLE (-3365 2085);
FORCEPROP 1 LASTPIN (-3375 2075) BN 7
J 0
(-3387 2083);
DISPLAY 0.489362 (-3387 2083);
PAINT GREEN (-3387 2083);
FORCEPROP 2 LAST CDS_LIB mstr_standard
J 2
(-3325 2075);
DISPLAY 0.723404 (-3325 2075);
PAINT MONO (-3325 2075);
DISPLAY INVISIBLE (-3325 2075);
FORCEPROP 1 LAST BODY_TYPE PLUMBING
J 0
(-3325 2125);
DISPLAY 0.872340 (-3325 2125);
PAINT GREEN (-3325 2125);
DISPLAY INVISIBLE (-3325 2125);
FORCEPROP 1 LAST HDL_TAP TRUE
J 0
(-3000 1950);
DISPLAY 0.872340 (-3000 1950);
DISPLAY INVISIBLE (-3000 1950);
FORCEPROP 1 LAST PATH I234
J 0
(-3327 2075);
DISPLAY 0.872340 (-3327 2075);
PAINT GREEN (-3327 2075);
DISPLAY INVISIBLE (-3327 2075);
FORCEADD OFFPAGE..6
R 2
(-2725 2025);
FORCEPROP 2 LAST $XR0 101 
J 0
(-2511 2025);
DISPLAY 0.638298 (-2511 2025);
PAINT MONO (-2511 2025);
FORCEPROP 2 LAST CDS_LIB mstr_standard
J 2
(-2725 2025);
DISPLAY 0.723404 (-2725 2025);
PAINT MONO (-2725 2025);
DISPLAY INVISIBLE (-2725 2025);
FORCEPROP 1 LAST OFFPAGE TRUE
J 2
(-3050 1900);
DISPLAY 0.872340 (-3050 1900);
PAINT GREEN (-3050 1900);
DISPLAY INVISIBLE (-3050 1900);
FORCEPROP 1 LAST COMMENT_BODY TRUE
J 2
(-2825 1950);
DISPLAY 0.872340 (-2825 1950);
PAINT GREEN (-2825 1950);
DISPLAY INVISIBLE (-2825 1950);
FORCEPROP 2 LAST PATH I235
J 0
(-2500 2075);
DISPLAY 1.021277 (-2500 2075);
DISPLAY INVISIBLE (-2500 2075);
FORCEADD TAP..1
(-3325 1925);
FORCEPROP 3 LASTPIN (-3375 1925) SIG_NAME M_D_CPU1_SB_CB<1>
J 0
(-3365 1935);
DISPLAY 0.659574 (-3365 1935);
PAINT MONO (-3365 1935);
DISPLAY INVISIBLE (-3365 1935);
FORCEPROP 1 LASTPIN (-3375 1925) BN 1
J 0
(-3387 1933);
DISPLAY 0.489362 (-3387 1933);
PAINT GREEN (-3387 1933);
FORCEPROP 2 LAST CDS_LIB mstr_standard
J 2
(-3325 1925);
DISPLAY 0.723404 (-3325 1925);
PAINT MONO (-3325 1925);
DISPLAY INVISIBLE (-3325 1925);
FORCEPROP 1 LAST BODY_TYPE PLUMBING
J 0
(-3325 1975);
DISPLAY 0.872340 (-3325 1975);
PAINT GREEN (-3325 1975);
DISPLAY INVISIBLE (-3325 1975);
FORCEPROP 1 LAST HDL_TAP TRUE
J 0
(-3000 1800);
DISPLAY 0.872340 (-3000 1800);
DISPLAY INVISIBLE (-3000 1800);
FORCEPROP 1 LAST PATH I236
J 0
(-3327 1925);
DISPLAY 0.872340 (-3327 1925);
PAINT GREEN (-3327 1925);
DISPLAY INVISIBLE (-3327 1925);
FORCEADD TAP..1
(-3325 1975);
FORCEPROP 3 LASTPIN (-3375 1975) SIG_NAME M_D_CPU1_SB_CB<0>
J 0
(-3365 1985);
DISPLAY 0.659574 (-3365 1985);
PAINT MONO (-3365 1985);
DISPLAY INVISIBLE (-3365 1985);
FORCEPROP 1 LASTPIN (-3375 1975) BN 0
J 0
(-3387 1983);
DISPLAY 0.489362 (-3387 1983);
PAINT GREEN (-3387 1983);
FORCEPROP 2 LAST CDS_LIB mstr_standard
J 2
(-3325 1975);
DISPLAY 0.723404 (-3325 1975);
PAINT MONO (-3325 1975);
DISPLAY INVISIBLE (-3325 1975);
FORCEPROP 1 LAST BODY_TYPE PLUMBING
J 0
(-3325 2025);
DISPLAY 0.872340 (-3325 2025);
PAINT GREEN (-3325 2025);
DISPLAY INVISIBLE (-3325 2025);
FORCEPROP 1 LAST HDL_TAP TRUE
J 0
(-3000 1850);
DISPLAY 0.872340 (-3000 1850);
DISPLAY INVISIBLE (-3000 1850);
FORCEPROP 1 LAST PATH I237
J 0
(-3327 1975);
DISPLAY 0.872340 (-3327 1975);
PAINT GREEN (-3327 1975);
DISPLAY INVISIBLE (-3327 1975);
FORCEADD TAP..1
(-3325 1825);
FORCEPROP 3 LASTPIN (-3375 1825) SIG_NAME M_D_CPU1_SB_CB<3>
J 0
(-3365 1835);
DISPLAY 0.659574 (-3365 1835);
PAINT MONO (-3365 1835);
DISPLAY INVISIBLE (-3365 1835);
FORCEPROP 1 LASTPIN (-3375 1825) BN 3
J 0
(-3387 1833);
DISPLAY 0.489362 (-3387 1833);
PAINT GREEN (-3387 1833);
FORCEPROP 2 LAST CDS_LIB mstr_standard
J 2
(-3325 1825);
DISPLAY 0.723404 (-3325 1825);
PAINT MONO (-3325 1825);
DISPLAY INVISIBLE (-3325 1825);
FORCEPROP 1 LAST BODY_TYPE PLUMBING
J 0
(-3325 1875);
DISPLAY 0.872340 (-3325 1875);
PAINT GREEN (-3325 1875);
DISPLAY INVISIBLE (-3325 1875);
FORCEPROP 1 LAST HDL_TAP TRUE
J 0
(-3000 1700);
DISPLAY 0.872340 (-3000 1700);
DISPLAY INVISIBLE (-3000 1700);
FORCEPROP 1 LAST PATH I238
J 0
(-3327 1825);
DISPLAY 0.872340 (-3327 1825);
PAINT GREEN (-3327 1825);
DISPLAY INVISIBLE (-3327 1825);
FORCEADD TAP..1
(-3325 1875);
FORCEPROP 3 LASTPIN (-3375 1875) SIG_NAME M_D_CPU1_SB_CB<2>
J 0
(-3365 1885);
DISPLAY 0.659574 (-3365 1885);
PAINT MONO (-3365 1885);
DISPLAY INVISIBLE (-3365 1885);
FORCEPROP 1 LASTPIN (-3375 1875) BN 2
J 0
(-3387 1883);
DISPLAY 0.489362 (-3387 1883);
PAINT GREEN (-3387 1883);
FORCEPROP 2 LAST CDS_LIB mstr_standard
J 2
(-3325 1875);
DISPLAY 0.723404 (-3325 1875);
PAINT MONO (-3325 1875);
DISPLAY INVISIBLE (-3325 1875);
FORCEPROP 1 LAST BODY_TYPE PLUMBING
J 0
(-3325 1925);
DISPLAY 0.872340 (-3325 1925);
PAINT GREEN (-3325 1925);
DISPLAY INVISIBLE (-3325 1925);
FORCEPROP 1 LAST HDL_TAP TRUE
J 0
(-3000 1750);
DISPLAY 0.872340 (-3000 1750);
DISPLAY INVISIBLE (-3000 1750);
FORCEPROP 1 LAST PATH I239
J 0
(-3327 1875);
DISPLAY 0.872340 (-3327 1875);
PAINT GREEN (-3327 1875);
DISPLAY INVISIBLE (-3327 1875);
FORCEADD TAP..1
(-3325 1625);
FORCEPROP 3 LASTPIN (-3375 1625) SIG_NAME M_D_CPU1_SB_CB<7>
J 0
(-3365 1635);
DISPLAY 0.659574 (-3365 1635);
PAINT MONO (-3365 1635);
DISPLAY INVISIBLE (-3365 1635);
FORCEPROP 1 LASTPIN (-3375 1625) BN 7
J 0
(-3387 1633);
DISPLAY 0.489362 (-3387 1633);
PAINT GREEN (-3387 1633);
FORCEPROP 2 LAST CDS_LIB mstr_standard
J 2
(-3325 1625);
DISPLAY 0.723404 (-3325 1625);
PAINT MONO (-3325 1625);
DISPLAY INVISIBLE (-3325 1625);
FORCEPROP 1 LAST BODY_TYPE PLUMBING
J 0
(-3325 1675);
DISPLAY 0.872340 (-3325 1675);
PAINT GREEN (-3325 1675);
DISPLAY INVISIBLE (-3325 1675);
FORCEPROP 1 LAST HDL_TAP TRUE
J 0
(-3000 1500);
DISPLAY 0.872340 (-3000 1500);
DISPLAY INVISIBLE (-3000 1500);
FORCEPROP 1 LAST PATH I240
J 0
(-3327 1625);
DISPLAY 0.872340 (-3327 1625);
PAINT GREEN (-3327 1625);
DISPLAY INVISIBLE (-3327 1625);
FORCEADD TAP..1
(-3325 1675);
FORCEPROP 3 LASTPIN (-3375 1675) SIG_NAME M_D_CPU1_SB_CB<6>
J 0
(-3365 1685);
DISPLAY 0.659574 (-3365 1685);
PAINT MONO (-3365 1685);
DISPLAY INVISIBLE (-3365 1685);
FORCEPROP 1 LASTPIN (-3375 1675) BN 6
J 0
(-3387 1683);
DISPLAY 0.489362 (-3387 1683);
PAINT GREEN (-3387 1683);
FORCEPROP 2 LAST CDS_LIB mstr_standard
J 2
(-3325 1675);
DISPLAY 0.723404 (-3325 1675);
PAINT MONO (-3325 1675);
DISPLAY INVISIBLE (-3325 1675);
FORCEPROP 1 LAST BODY_TYPE PLUMBING
J 0
(-3325 1725);
DISPLAY 0.872340 (-3325 1725);
PAINT GREEN (-3325 1725);
DISPLAY INVISIBLE (-3325 1725);
FORCEPROP 1 LAST HDL_TAP TRUE
J 0
(-3000 1550);
DISPLAY 0.872340 (-3000 1550);
DISPLAY INVISIBLE (-3000 1550);
FORCEPROP 1 LAST PATH I241
J 0
(-3327 1675);
DISPLAY 0.872340 (-3327 1675);
PAINT GREEN (-3327 1675);
DISPLAY INVISIBLE (-3327 1675);
FORCEADD TAP..1
(-3325 1775);
FORCEPROP 3 LASTPIN (-3375 1775) SIG_NAME M_D_CPU1_SB_CB<4>
J 0
(-3365 1785);
DISPLAY 0.659574 (-3365 1785);
PAINT MONO (-3365 1785);
DISPLAY INVISIBLE (-3365 1785);
FORCEPROP 1 LASTPIN (-3375 1775) BN 4
J 0
(-3387 1783);
DISPLAY 0.489362 (-3387 1783);
PAINT GREEN (-3387 1783);
FORCEPROP 2 LAST CDS_LIB mstr_standard
J 2
(-3325 1775);
DISPLAY 0.723404 (-3325 1775);
PAINT MONO (-3325 1775);
DISPLAY INVISIBLE (-3325 1775);
FORCEPROP 1 LAST BODY_TYPE PLUMBING
J 0
(-3325 1825);
DISPLAY 0.872340 (-3325 1825);
PAINT GREEN (-3325 1825);
DISPLAY INVISIBLE (-3325 1825);
FORCEPROP 1 LAST HDL_TAP TRUE
J 0
(-3000 1650);
DISPLAY 0.872340 (-3000 1650);
DISPLAY INVISIBLE (-3000 1650);
FORCEPROP 1 LAST PATH I242
J 0
(-3327 1775);
DISPLAY 0.872340 (-3327 1775);
PAINT GREEN (-3327 1775);
DISPLAY INVISIBLE (-3327 1775);
FORCEADD TAP..1
(-3325 1725);
FORCEPROP 3 LASTPIN (-3375 1725) SIG_NAME M_D_CPU1_SB_CB<5>
J 0
(-3365 1735);
DISPLAY 0.659574 (-3365 1735);
PAINT MONO (-3365 1735);
DISPLAY INVISIBLE (-3365 1735);
FORCEPROP 1 LASTPIN (-3375 1725) BN 5
J 0
(-3387 1733);
DISPLAY 0.489362 (-3387 1733);
PAINT GREEN (-3387 1733);
FORCEPROP 2 LAST CDS_LIB mstr_standard
J 2
(-3325 1725);
DISPLAY 0.723404 (-3325 1725);
PAINT MONO (-3325 1725);
DISPLAY INVISIBLE (-3325 1725);
FORCEPROP 1 LAST BODY_TYPE PLUMBING
J 0
(-3325 1775);
DISPLAY 0.872340 (-3325 1775);
PAINT GREEN (-3325 1775);
DISPLAY INVISIBLE (-3325 1775);
FORCEPROP 1 LAST HDL_TAP TRUE
J 0
(-3000 1600);
DISPLAY 0.872340 (-3000 1600);
DISPLAY INVISIBLE (-3000 1600);
FORCEPROP 1 LAST PATH I243
J 0
(-3327 1725);
DISPLAY 0.872340 (-3327 1725);
PAINT GREEN (-3327 1725);
DISPLAY INVISIBLE (-3327 1725);
FORCEADD TAP..1
R 2
(-5750 6025);
FORCEPROP 3 LASTPIN (-5700 6025) SIG_NAME M_D_CPU1_SA_DQS_DP<0>
J 0
(-5690 6035);
DISPLAY 0.659574 (-5690 6035);
PAINT MONO (-5690 6035);
DISPLAY INVISIBLE (-5690 6035);
FORCEPROP 1 LASTPIN (-5700 6025) BN 0
J 2
(-5688 6033);
DISPLAY 0.489362 (-5688 6033);
PAINT GREEN (-5688 6033);
FORCEPROP 2 LAST CDS_LIB mstr_standard
J 2
(-5750 6025);
DISPLAY 0.723404 (-5750 6025);
PAINT MONO (-5750 6025);
DISPLAY INVISIBLE (-5750 6025);
FORCEPROP 1 LAST BODY_TYPE PLUMBING
J 2
(-5750 6075);
DISPLAY 0.872340 (-5750 6075);
PAINT GREEN (-5750 6075);
DISPLAY INVISIBLE (-5750 6075);
FORCEPROP 1 LAST HDL_TAP TRUE
J 2
(-6075 5900);
DISPLAY 0.872340 (-6075 5900);
DISPLAY INVISIBLE (-6075 5900);
FORCEPROP 1 LAST PATH I244
J 2
(-5748 6025);
DISPLAY 0.872340 (-5748 6025);
PAINT GREEN (-5748 6025);
DISPLAY INVISIBLE (-5748 6025);
FORCEADD TAP..1
R 2
(-5750 5925);
FORCEPROP 3 LASTPIN (-5700 5925) SIG_NAME M_D_CPU1_SA_DQS_DP<1>
J 0
(-5690 5935);
DISPLAY 0.659574 (-5690 5935);
PAINT MONO (-5690 5935);
DISPLAY INVISIBLE (-5690 5935);
FORCEPROP 1 LASTPIN (-5700 5925) BN 1
J 2
(-5688 5933);
DISPLAY 0.489362 (-5688 5933);
PAINT GREEN (-5688 5933);
FORCEPROP 2 LAST CDS_LIB mstr_standard
J 2
(-5750 5925);
DISPLAY 0.723404 (-5750 5925);
PAINT MONO (-5750 5925);
DISPLAY INVISIBLE (-5750 5925);
FORCEPROP 1 LAST BODY_TYPE PLUMBING
J 2
(-5750 5975);
DISPLAY 0.872340 (-5750 5975);
PAINT GREEN (-5750 5975);
DISPLAY INVISIBLE (-5750 5975);
FORCEPROP 1 LAST HDL_TAP TRUE
J 2
(-6075 5800);
DISPLAY 0.872340 (-6075 5800);
DISPLAY INVISIBLE (-6075 5800);
FORCEPROP 1 LAST PATH I245
J 2
(-5748 5925);
DISPLAY 0.872340 (-5748 5925);
PAINT GREEN (-5748 5925);
DISPLAY INVISIBLE (-5748 5925);
FORCEADD TAP..1
R 2
(-5750 5825);
FORCEPROP 3 LASTPIN (-5700 5825) SIG_NAME M_D_CPU1_SA_DQS_DP<2>
J 0
(-5690 5835);
DISPLAY 0.659574 (-5690 5835);
PAINT MONO (-5690 5835);
DISPLAY INVISIBLE (-5690 5835);
FORCEPROP 1 LASTPIN (-5700 5825) BN 2
J 2
(-5688 5833);
DISPLAY 0.489362 (-5688 5833);
PAINT GREEN (-5688 5833);
FORCEPROP 2 LAST CDS_LIB mstr_standard
J 2
(-5750 5825);
DISPLAY 0.723404 (-5750 5825);
PAINT MONO (-5750 5825);
DISPLAY INVISIBLE (-5750 5825);
FORCEPROP 1 LAST BODY_TYPE PLUMBING
J 2
(-5750 5875);
DISPLAY 0.872340 (-5750 5875);
PAINT GREEN (-5750 5875);
DISPLAY INVISIBLE (-5750 5875);
FORCEPROP 1 LAST HDL_TAP TRUE
J 2
(-6075 5700);
DISPLAY 0.872340 (-6075 5700);
DISPLAY INVISIBLE (-6075 5700);
FORCEPROP 1 LAST PATH I246
J 2
(-5748 5825);
DISPLAY 0.872340 (-5748 5825);
PAINT GREEN (-5748 5825);
DISPLAY INVISIBLE (-5748 5825);
FORCEADD TAP..1
R 2
(-5750 5725);
FORCEPROP 3 LASTPIN (-5700 5725) SIG_NAME M_D_CPU1_SA_DQS_DP<3>
J 0
(-5690 5735);
DISPLAY 0.659574 (-5690 5735);
PAINT MONO (-5690 5735);
DISPLAY INVISIBLE (-5690 5735);
FORCEPROP 1 LASTPIN (-5700 5725) BN 3
J 2
(-5688 5733);
DISPLAY 0.489362 (-5688 5733);
PAINT GREEN (-5688 5733);
FORCEPROP 2 LAST CDS_LIB mstr_standard
J 2
(-5750 5725);
DISPLAY 0.723404 (-5750 5725);
PAINT MONO (-5750 5725);
DISPLAY INVISIBLE (-5750 5725);
FORCEPROP 1 LAST BODY_TYPE PLUMBING
J 2
(-5750 5775);
DISPLAY 0.872340 (-5750 5775);
PAINT GREEN (-5750 5775);
DISPLAY INVISIBLE (-5750 5775);
FORCEPROP 1 LAST HDL_TAP TRUE
J 2
(-6075 5600);
DISPLAY 0.872340 (-6075 5600);
DISPLAY INVISIBLE (-6075 5600);
FORCEPROP 1 LAST PATH I247
J 2
(-5748 5725);
DISPLAY 0.872340 (-5748 5725);
PAINT GREEN (-5748 5725);
DISPLAY INVISIBLE (-5748 5725);
FORCEADD TAP..1
R 2
(-5950 5975);
FORCEPROP 3 LASTPIN (-5900 5975) SIG_NAME M_D_CPU1_SA_DQS_DN<0>
J 0
(-5890 5985);
DISPLAY 0.659574 (-5890 5985);
PAINT MONO (-5890 5985);
DISPLAY INVISIBLE (-5890 5985);
FORCEPROP 1 LASTPIN (-5900 5975) BN 0
J 2
(-5888 5983);
DISPLAY 0.489362 (-5888 5983);
PAINT GREEN (-5888 5983);
FORCEPROP 2 LAST CDS_LIB mstr_standard
J 2
(-5950 5975);
DISPLAY 0.723404 (-5950 5975);
PAINT MONO (-5950 5975);
DISPLAY INVISIBLE (-5950 5975);
FORCEPROP 1 LAST BODY_TYPE PLUMBING
J 2
(-5950 6025);
DISPLAY 0.872340 (-5950 6025);
PAINT GREEN (-5950 6025);
DISPLAY INVISIBLE (-5950 6025);
FORCEPROP 1 LAST HDL_TAP TRUE
J 2
(-6275 5850);
DISPLAY 0.872340 (-6275 5850);
DISPLAY INVISIBLE (-6275 5850);
FORCEPROP 1 LAST PATH I248
J 2
(-5948 5975);
DISPLAY 0.872340 (-5948 5975);
PAINT GREEN (-5948 5975);
DISPLAY INVISIBLE (-5948 5975);
FORCEADD TAP..1
R 2
(-5950 5875);
FORCEPROP 3 LASTPIN (-5900 5875) SIG_NAME M_D_CPU1_SA_DQS_DN<1>
J 0
(-5890 5885);
DISPLAY 0.659574 (-5890 5885);
PAINT MONO (-5890 5885);
DISPLAY INVISIBLE (-5890 5885);
FORCEPROP 1 LASTPIN (-5900 5875) BN 1
J 2
(-5888 5883);
DISPLAY 0.489362 (-5888 5883);
PAINT GREEN (-5888 5883);
FORCEPROP 2 LAST CDS_LIB mstr_standard
J 2
(-5950 5875);
DISPLAY 0.723404 (-5950 5875);
PAINT MONO (-5950 5875);
DISPLAY INVISIBLE (-5950 5875);
FORCEPROP 1 LAST BODY_TYPE PLUMBING
J 2
(-5950 5925);
DISPLAY 0.872340 (-5950 5925);
PAINT GREEN (-5950 5925);
DISPLAY INVISIBLE (-5950 5925);
FORCEPROP 1 LAST HDL_TAP TRUE
J 2
(-6275 5750);
DISPLAY 0.872340 (-6275 5750);
DISPLAY INVISIBLE (-6275 5750);
FORCEPROP 1 LAST PATH I249
J 2
(-5948 5875);
DISPLAY 0.872340 (-5948 5875);
PAINT GREEN (-5948 5875);
DISPLAY INVISIBLE (-5948 5875);
FORCEADD TAP..1
R 2
(-5950 5775);
FORCEPROP 3 LASTPIN (-5900 5775) SIG_NAME M_D_CPU1_SA_DQS_DN<2>
J 0
(-5890 5785);
DISPLAY 0.659574 (-5890 5785);
PAINT MONO (-5890 5785);
DISPLAY INVISIBLE (-5890 5785);
FORCEPROP 1 LASTPIN (-5900 5775) BN 2
J 2
(-5888 5783);
DISPLAY 0.489362 (-5888 5783);
PAINT GREEN (-5888 5783);
FORCEPROP 2 LAST CDS_LIB mstr_standard
J 2
(-5950 5775);
DISPLAY 0.723404 (-5950 5775);
PAINT MONO (-5950 5775);
DISPLAY INVISIBLE (-5950 5775);
FORCEPROP 1 LAST BODY_TYPE PLUMBING
J 2
(-5950 5825);
DISPLAY 0.872340 (-5950 5825);
PAINT GREEN (-5950 5825);
DISPLAY INVISIBLE (-5950 5825);
FORCEPROP 1 LAST HDL_TAP TRUE
J 2
(-6275 5650);
DISPLAY 0.872340 (-6275 5650);
DISPLAY INVISIBLE (-6275 5650);
FORCEPROP 1 LAST PATH I250
J 2
(-5948 5775);
DISPLAY 0.872340 (-5948 5775);
PAINT GREEN (-5948 5775);
DISPLAY INVISIBLE (-5948 5775);
FORCEADD TAP..1
R 2
(-5950 5675);
FORCEPROP 3 LASTPIN (-5900 5675) SIG_NAME M_D_CPU1_SA_DQS_DN<3>
J 0
(-5890 5685);
DISPLAY 0.659574 (-5890 5685);
PAINT MONO (-5890 5685);
DISPLAY INVISIBLE (-5890 5685);
FORCEPROP 1 LASTPIN (-5900 5675) BN 3
J 2
(-5888 5683);
DISPLAY 0.489362 (-5888 5683);
PAINT GREEN (-5888 5683);
FORCEPROP 2 LAST CDS_LIB mstr_standard
J 2
(-5950 5675);
DISPLAY 0.723404 (-5950 5675);
PAINT MONO (-5950 5675);
DISPLAY INVISIBLE (-5950 5675);
FORCEPROP 1 LAST BODY_TYPE PLUMBING
J 2
(-5950 5725);
DISPLAY 0.872340 (-5950 5725);
PAINT GREEN (-5950 5725);
DISPLAY INVISIBLE (-5950 5725);
FORCEPROP 1 LAST HDL_TAP TRUE
J 2
(-6275 5550);
DISPLAY 0.872340 (-6275 5550);
DISPLAY INVISIBLE (-6275 5550);
FORCEPROP 1 LAST PATH I251
J 2
(-5948 5675);
DISPLAY 0.872340 (-5948 5675);
PAINT GREEN (-5948 5675);
DISPLAY INVISIBLE (-5948 5675);
FORCEADD TAP..1
R 2
(-5750 5625);
FORCEPROP 3 LASTPIN (-5700 5625) SIG_NAME M_D_CPU1_SA_DQS_DP<4>
J 0
(-5690 5635);
DISPLAY 0.659574 (-5690 5635);
PAINT MONO (-5690 5635);
DISPLAY INVISIBLE (-5690 5635);
FORCEPROP 1 LASTPIN (-5700 5625) BN 4
J 2
(-5688 5633);
DISPLAY 0.489362 (-5688 5633);
PAINT GREEN (-5688 5633);
FORCEPROP 2 LAST CDS_LIB mstr_standard
J 2
(-5750 5625);
DISPLAY 0.723404 (-5750 5625);
PAINT MONO (-5750 5625);
DISPLAY INVISIBLE (-5750 5625);
FORCEPROP 1 LAST BODY_TYPE PLUMBING
J 2
(-5750 5675);
DISPLAY 0.872340 (-5750 5675);
PAINT GREEN (-5750 5675);
DISPLAY INVISIBLE (-5750 5675);
FORCEPROP 1 LAST HDL_TAP TRUE
J 2
(-6075 5500);
DISPLAY 0.872340 (-6075 5500);
DISPLAY INVISIBLE (-6075 5500);
FORCEPROP 1 LAST PATH I252
J 2
(-5748 5625);
DISPLAY 0.872340 (-5748 5625);
PAINT GREEN (-5748 5625);
DISPLAY INVISIBLE (-5748 5625);
FORCEADD TAP..1
R 2
(-5750 5525);
FORCEPROP 3 LASTPIN (-5700 5525) SIG_NAME M_D_CPU1_SA_DQS_DP<5>
J 0
(-5690 5535);
DISPLAY 0.659574 (-5690 5535);
PAINT MONO (-5690 5535);
DISPLAY INVISIBLE (-5690 5535);
FORCEPROP 1 LASTPIN (-5700 5525) BN 5
J 2
(-5688 5533);
DISPLAY 0.489362 (-5688 5533);
PAINT GREEN (-5688 5533);
FORCEPROP 2 LAST CDS_LIB mstr_standard
J 2
(-5750 5525);
DISPLAY 0.723404 (-5750 5525);
PAINT MONO (-5750 5525);
DISPLAY INVISIBLE (-5750 5525);
FORCEPROP 1 LAST BODY_TYPE PLUMBING
J 2
(-5750 5575);
DISPLAY 0.872340 (-5750 5575);
PAINT GREEN (-5750 5575);
DISPLAY INVISIBLE (-5750 5575);
FORCEPROP 1 LAST HDL_TAP TRUE
J 2
(-6075 5400);
DISPLAY 0.872340 (-6075 5400);
DISPLAY INVISIBLE (-6075 5400);
FORCEPROP 1 LAST PATH I253
J 2
(-5748 5525);
DISPLAY 0.872340 (-5748 5525);
PAINT GREEN (-5748 5525);
DISPLAY INVISIBLE (-5748 5525);
FORCEADD TAP..1
R 2
(-5750 5425);
FORCEPROP 3 LASTPIN (-5700 5425) SIG_NAME M_D_CPU1_SA_DQS_DP<6>
J 0
(-5690 5435);
DISPLAY 0.659574 (-5690 5435);
PAINT MONO (-5690 5435);
DISPLAY INVISIBLE (-5690 5435);
FORCEPROP 1 LASTPIN (-5700 5425) BN 6
J 2
(-5688 5433);
DISPLAY 0.489362 (-5688 5433);
PAINT GREEN (-5688 5433);
FORCEPROP 2 LAST CDS_LIB mstr_standard
J 2
(-5750 5425);
DISPLAY 0.723404 (-5750 5425);
PAINT MONO (-5750 5425);
DISPLAY INVISIBLE (-5750 5425);
FORCEPROP 1 LAST BODY_TYPE PLUMBING
J 2
(-5750 5475);
DISPLAY 0.872340 (-5750 5475);
PAINT GREEN (-5750 5475);
DISPLAY INVISIBLE (-5750 5475);
FORCEPROP 1 LAST HDL_TAP TRUE
J 2
(-6075 5300);
DISPLAY 0.872340 (-6075 5300);
DISPLAY INVISIBLE (-6075 5300);
FORCEPROP 1 LAST PATH I254
J 2
(-5748 5425);
DISPLAY 0.872340 (-5748 5425);
PAINT GREEN (-5748 5425);
DISPLAY INVISIBLE (-5748 5425);
FORCEADD TAP..1
R 2
(-5750 5325);
FORCEPROP 3 LASTPIN (-5700 5325) SIG_NAME M_D_CPU1_SA_DQS_DP<7>
J 0
(-5690 5335);
DISPLAY 0.659574 (-5690 5335);
PAINT MONO (-5690 5335);
DISPLAY INVISIBLE (-5690 5335);
FORCEPROP 1 LASTPIN (-5700 5325) BN 7
J 2
(-5688 5333);
DISPLAY 0.489362 (-5688 5333);
PAINT GREEN (-5688 5333);
FORCEPROP 2 LAST CDS_LIB mstr_standard
J 2
(-5750 5325);
DISPLAY 0.723404 (-5750 5325);
PAINT MONO (-5750 5325);
DISPLAY INVISIBLE (-5750 5325);
FORCEPROP 1 LAST BODY_TYPE PLUMBING
J 2
(-5750 5375);
DISPLAY 0.872340 (-5750 5375);
PAINT GREEN (-5750 5375);
DISPLAY INVISIBLE (-5750 5375);
FORCEPROP 1 LAST HDL_TAP TRUE
J 2
(-6075 5200);
DISPLAY 0.872340 (-6075 5200);
DISPLAY INVISIBLE (-6075 5200);
FORCEPROP 1 LAST PATH I255
J 2
(-5748 5325);
DISPLAY 0.872340 (-5748 5325);
PAINT GREEN (-5748 5325);
DISPLAY INVISIBLE (-5748 5325);
FORCEADD TAP..1
R 2
(-5750 5225);
FORCEPROP 3 LASTPIN (-5700 5225) SIG_NAME M_D_CPU1_SA_DQS_DP<8>
J 0
(-5690 5235);
DISPLAY 0.659574 (-5690 5235);
PAINT MONO (-5690 5235);
DISPLAY INVISIBLE (-5690 5235);
FORCEPROP 1 LASTPIN (-5700 5225) BN 8
J 2
(-5688 5233);
DISPLAY 0.489362 (-5688 5233);
PAINT GREEN (-5688 5233);
FORCEPROP 2 LAST CDS_LIB mstr_standard
J 2
(-5750 5225);
DISPLAY 0.723404 (-5750 5225);
PAINT MONO (-5750 5225);
DISPLAY INVISIBLE (-5750 5225);
FORCEPROP 1 LAST BODY_TYPE PLUMBING
J 2
(-5750 5275);
DISPLAY 0.872340 (-5750 5275);
PAINT GREEN (-5750 5275);
DISPLAY INVISIBLE (-5750 5275);
FORCEPROP 1 LAST HDL_TAP TRUE
J 2
(-6075 5100);
DISPLAY 0.872340 (-6075 5100);
DISPLAY INVISIBLE (-6075 5100);
FORCEPROP 1 LAST PATH I256
J 2
(-5748 5225);
DISPLAY 0.872340 (-5748 5225);
PAINT GREEN (-5748 5225);
DISPLAY INVISIBLE (-5748 5225);
FORCEADD TAP..1
R 2
(-5750 5125);
FORCEPROP 3 LASTPIN (-5700 5125) SIG_NAME M_D_CPU1_SA_DQS_DP<9>
J 0
(-5690 5135);
DISPLAY 0.659574 (-5690 5135);
PAINT MONO (-5690 5135);
DISPLAY INVISIBLE (-5690 5135);
FORCEPROP 1 LASTPIN (-5700 5125) BN 9
J 2
(-5688 5133);
DISPLAY 0.489362 (-5688 5133);
PAINT GREEN (-5688 5133);
FORCEPROP 2 LAST CDS_LIB mstr_standard
J 2
(-5750 5125);
DISPLAY 0.723404 (-5750 5125);
PAINT MONO (-5750 5125);
DISPLAY INVISIBLE (-5750 5125);
FORCEPROP 1 LAST BODY_TYPE PLUMBING
J 2
(-5750 5175);
DISPLAY 0.872340 (-5750 5175);
PAINT GREEN (-5750 5175);
DISPLAY INVISIBLE (-5750 5175);
FORCEPROP 1 LAST HDL_TAP TRUE
J 2
(-6075 5000);
DISPLAY 0.872340 (-6075 5000);
DISPLAY INVISIBLE (-6075 5000);
FORCEPROP 1 LAST PATH I257
J 2
(-5748 5125);
DISPLAY 0.872340 (-5748 5125);
PAINT GREEN (-5748 5125);
DISPLAY INVISIBLE (-5748 5125);
FORCEADD TAP..1
R 2
(-5950 5575);
FORCEPROP 3 LASTPIN (-5900 5575) SIG_NAME M_D_CPU1_SA_DQS_DN<4>
J 0
(-5890 5585);
DISPLAY 0.659574 (-5890 5585);
PAINT MONO (-5890 5585);
DISPLAY INVISIBLE (-5890 5585);
FORCEPROP 1 LASTPIN (-5900 5575) BN 4
J 2
(-5888 5583);
DISPLAY 0.489362 (-5888 5583);
PAINT GREEN (-5888 5583);
FORCEPROP 2 LAST CDS_LIB mstr_standard
J 2
(-5950 5575);
DISPLAY 0.723404 (-5950 5575);
PAINT MONO (-5950 5575);
DISPLAY INVISIBLE (-5950 5575);
FORCEPROP 1 LAST BODY_TYPE PLUMBING
J 2
(-5950 5625);
DISPLAY 0.872340 (-5950 5625);
PAINT GREEN (-5950 5625);
DISPLAY INVISIBLE (-5950 5625);
FORCEPROP 1 LAST HDL_TAP TRUE
J 2
(-6275 5450);
DISPLAY 0.872340 (-6275 5450);
DISPLAY INVISIBLE (-6275 5450);
FORCEPROP 1 LAST PATH I258
J 2
(-5948 5575);
DISPLAY 0.872340 (-5948 5575);
PAINT GREEN (-5948 5575);
DISPLAY INVISIBLE (-5948 5575);
FORCEADD TAP..1
R 2
(-5950 5475);
FORCEPROP 3 LASTPIN (-5900 5475) SIG_NAME M_D_CPU1_SA_DQS_DN<5>
J 0
(-5890 5485);
DISPLAY 0.659574 (-5890 5485);
PAINT MONO (-5890 5485);
DISPLAY INVISIBLE (-5890 5485);
FORCEPROP 1 LASTPIN (-5900 5475) BN 5
J 2
(-5888 5483);
DISPLAY 0.489362 (-5888 5483);
PAINT GREEN (-5888 5483);
FORCEPROP 2 LAST CDS_LIB mstr_standard
J 2
(-5950 5475);
DISPLAY 0.723404 (-5950 5475);
PAINT MONO (-5950 5475);
DISPLAY INVISIBLE (-5950 5475);
FORCEPROP 1 LAST BODY_TYPE PLUMBING
J 2
(-5950 5525);
DISPLAY 0.872340 (-5950 5525);
PAINT GREEN (-5950 5525);
DISPLAY INVISIBLE (-5950 5525);
FORCEPROP 1 LAST HDL_TAP TRUE
J 2
(-6275 5350);
DISPLAY 0.872340 (-6275 5350);
DISPLAY INVISIBLE (-6275 5350);
FORCEPROP 1 LAST PATH I259
J 2
(-5948 5475);
DISPLAY 0.872340 (-5948 5475);
PAINT GREEN (-5948 5475);
DISPLAY INVISIBLE (-5948 5475);
FORCEADD TAP..1
R 2
(-5950 5375);
FORCEPROP 3 LASTPIN (-5900 5375) SIG_NAME M_D_CPU1_SA_DQS_DN<6>
J 0
(-5890 5385);
DISPLAY 0.659574 (-5890 5385);
PAINT MONO (-5890 5385);
DISPLAY INVISIBLE (-5890 5385);
FORCEPROP 1 LASTPIN (-5900 5375) BN 6
J 2
(-5888 5383);
DISPLAY 0.489362 (-5888 5383);
PAINT GREEN (-5888 5383);
FORCEPROP 2 LAST CDS_LIB mstr_standard
J 2
(-5950 5375);
DISPLAY 0.723404 (-5950 5375);
PAINT MONO (-5950 5375);
DISPLAY INVISIBLE (-5950 5375);
FORCEPROP 1 LAST BODY_TYPE PLUMBING
J 2
(-5950 5425);
DISPLAY 0.872340 (-5950 5425);
PAINT GREEN (-5950 5425);
DISPLAY INVISIBLE (-5950 5425);
FORCEPROP 1 LAST HDL_TAP TRUE
J 2
(-6275 5250);
DISPLAY 0.872340 (-6275 5250);
DISPLAY INVISIBLE (-6275 5250);
FORCEPROP 1 LAST PATH I260
J 2
(-5948 5375);
DISPLAY 0.872340 (-5948 5375);
PAINT GREEN (-5948 5375);
DISPLAY INVISIBLE (-5948 5375);
FORCEADD TAP..1
R 2
(-5950 5275);
FORCEPROP 3 LASTPIN (-5900 5275) SIG_NAME M_D_CPU1_SA_DQS_DN<7>
J 0
(-5890 5285);
DISPLAY 0.659574 (-5890 5285);
PAINT MONO (-5890 5285);
DISPLAY INVISIBLE (-5890 5285);
FORCEPROP 1 LASTPIN (-5900 5275) BN 7
J 2
(-5888 5283);
DISPLAY 0.489362 (-5888 5283);
PAINT GREEN (-5888 5283);
FORCEPROP 2 LAST CDS_LIB mstr_standard
J 2
(-5950 5275);
DISPLAY 0.723404 (-5950 5275);
PAINT MONO (-5950 5275);
DISPLAY INVISIBLE (-5950 5275);
FORCEPROP 1 LAST BODY_TYPE PLUMBING
J 2
(-5950 5325);
DISPLAY 0.872340 (-5950 5325);
PAINT GREEN (-5950 5325);
DISPLAY INVISIBLE (-5950 5325);
FORCEPROP 1 LAST HDL_TAP TRUE
J 2
(-6275 5150);
DISPLAY 0.872340 (-6275 5150);
DISPLAY INVISIBLE (-6275 5150);
FORCEPROP 1 LAST PATH I261
J 2
(-5948 5275);
DISPLAY 0.872340 (-5948 5275);
PAINT GREEN (-5948 5275);
DISPLAY INVISIBLE (-5948 5275);
FORCEADD TAP..1
R 2
(-5950 5175);
FORCEPROP 3 LASTPIN (-5900 5175) SIG_NAME M_D_CPU1_SA_DQS_DN<8>
J 0
(-5890 5185);
DISPLAY 0.659574 (-5890 5185);
PAINT MONO (-5890 5185);
DISPLAY INVISIBLE (-5890 5185);
FORCEPROP 1 LASTPIN (-5900 5175) BN 8
J 2
(-5888 5183);
DISPLAY 0.489362 (-5888 5183);
PAINT GREEN (-5888 5183);
FORCEPROP 2 LAST CDS_LIB mstr_standard
J 2
(-5950 5175);
DISPLAY 0.723404 (-5950 5175);
PAINT MONO (-5950 5175);
DISPLAY INVISIBLE (-5950 5175);
FORCEPROP 1 LAST BODY_TYPE PLUMBING
J 2
(-5950 5225);
DISPLAY 0.872340 (-5950 5225);
PAINT GREEN (-5950 5225);
DISPLAY INVISIBLE (-5950 5225);
FORCEPROP 1 LAST HDL_TAP TRUE
J 2
(-6275 5050);
DISPLAY 0.872340 (-6275 5050);
DISPLAY INVISIBLE (-6275 5050);
FORCEPROP 1 LAST PATH I262
J 2
(-5948 5175);
DISPLAY 0.872340 (-5948 5175);
PAINT GREEN (-5948 5175);
DISPLAY INVISIBLE (-5948 5175);
FORCEADD TAP..1
R 2
(-5750 4975);
FORCEPROP 3 LASTPIN (-5700 4975) SIG_NAME M_D_CPU1_SB_DQS_DP<0>
J 0
(-5690 4985);
DISPLAY 0.659574 (-5690 4985);
PAINT MONO (-5690 4985);
DISPLAY INVISIBLE (-5690 4985);
FORCEPROP 1 LASTPIN (-5700 4975) BN 0
J 2
(-5688 4983);
DISPLAY 0.489362 (-5688 4983);
PAINT GREEN (-5688 4983);
FORCEPROP 2 LAST CDS_LIB mstr_standard
J 2
(-5750 4975);
DISPLAY 0.723404 (-5750 4975);
PAINT MONO (-5750 4975);
DISPLAY INVISIBLE (-5750 4975);
FORCEPROP 1 LAST BODY_TYPE PLUMBING
J 2
(-5750 5025);
DISPLAY 0.872340 (-5750 5025);
PAINT GREEN (-5750 5025);
DISPLAY INVISIBLE (-5750 5025);
FORCEPROP 1 LAST HDL_TAP TRUE
J 2
(-6075 4850);
DISPLAY 0.872340 (-6075 4850);
DISPLAY INVISIBLE (-6075 4850);
FORCEPROP 1 LAST PATH I263
J 2
(-5748 4975);
DISPLAY 0.872340 (-5748 4975);
PAINT GREEN (-5748 4975);
DISPLAY INVISIBLE (-5748 4975);
FORCEADD TAP..1
R 2
(-5750 4875);
FORCEPROP 3 LASTPIN (-5700 4875) SIG_NAME M_D_CPU1_SB_DQS_DP<1>
J 0
(-5690 4885);
DISPLAY 0.659574 (-5690 4885);
PAINT MONO (-5690 4885);
DISPLAY INVISIBLE (-5690 4885);
FORCEPROP 1 LASTPIN (-5700 4875) BN 1
J 2
(-5688 4883);
DISPLAY 0.489362 (-5688 4883);
PAINT GREEN (-5688 4883);
FORCEPROP 2 LAST CDS_LIB mstr_standard
J 2
(-5750 4875);
DISPLAY 0.723404 (-5750 4875);
PAINT MONO (-5750 4875);
DISPLAY INVISIBLE (-5750 4875);
FORCEPROP 1 LAST BODY_TYPE PLUMBING
J 2
(-5750 4925);
DISPLAY 0.872340 (-5750 4925);
PAINT GREEN (-5750 4925);
DISPLAY INVISIBLE (-5750 4925);
FORCEPROP 1 LAST HDL_TAP TRUE
J 2
(-6075 4750);
DISPLAY 0.872340 (-6075 4750);
DISPLAY INVISIBLE (-6075 4750);
FORCEPROP 1 LAST PATH I264
J 2
(-5748 4875);
DISPLAY 0.872340 (-5748 4875);
PAINT GREEN (-5748 4875);
DISPLAY INVISIBLE (-5748 4875);
FORCEADD TAP..1
R 2
(-5750 4775);
FORCEPROP 3 LASTPIN (-5700 4775) SIG_NAME M_D_CPU1_SB_DQS_DP<2>
J 0
(-5690 4785);
DISPLAY 0.659574 (-5690 4785);
PAINT MONO (-5690 4785);
DISPLAY INVISIBLE (-5690 4785);
FORCEPROP 1 LASTPIN (-5700 4775) BN 2
J 2
(-5688 4783);
DISPLAY 0.489362 (-5688 4783);
PAINT GREEN (-5688 4783);
FORCEPROP 2 LAST CDS_LIB mstr_standard
J 2
(-5750 4775);
DISPLAY 0.723404 (-5750 4775);
PAINT MONO (-5750 4775);
DISPLAY INVISIBLE (-5750 4775);
FORCEPROP 1 LAST BODY_TYPE PLUMBING
J 2
(-5750 4825);
DISPLAY 0.872340 (-5750 4825);
PAINT GREEN (-5750 4825);
DISPLAY INVISIBLE (-5750 4825);
FORCEPROP 1 LAST HDL_TAP TRUE
J 2
(-6075 4650);
DISPLAY 0.872340 (-6075 4650);
DISPLAY INVISIBLE (-6075 4650);
FORCEPROP 1 LAST PATH I265
J 2
(-5748 4775);
DISPLAY 0.872340 (-5748 4775);
PAINT GREEN (-5748 4775);
DISPLAY INVISIBLE (-5748 4775);
FORCEADD TAP..1
R 2
(-5750 4675);
FORCEPROP 3 LASTPIN (-5700 4675) SIG_NAME M_D_CPU1_SB_DQS_DP<3>
J 0
(-5690 4685);
DISPLAY 0.659574 (-5690 4685);
PAINT MONO (-5690 4685);
DISPLAY INVISIBLE (-5690 4685);
FORCEPROP 1 LASTPIN (-5700 4675) BN 3
J 2
(-5688 4683);
DISPLAY 0.489362 (-5688 4683);
PAINT GREEN (-5688 4683);
FORCEPROP 2 LAST CDS_LIB mstr_standard
J 2
(-5750 4675);
DISPLAY 0.723404 (-5750 4675);
PAINT MONO (-5750 4675);
DISPLAY INVISIBLE (-5750 4675);
FORCEPROP 1 LAST BODY_TYPE PLUMBING
J 2
(-5750 4725);
DISPLAY 0.872340 (-5750 4725);
PAINT GREEN (-5750 4725);
DISPLAY INVISIBLE (-5750 4725);
FORCEPROP 1 LAST HDL_TAP TRUE
J 2
(-6075 4550);
DISPLAY 0.872340 (-6075 4550);
DISPLAY INVISIBLE (-6075 4550);
FORCEPROP 1 LAST PATH I266
J 2
(-5748 4675);
DISPLAY 0.872340 (-5748 4675);
PAINT GREEN (-5748 4675);
DISPLAY INVISIBLE (-5748 4675);
FORCEADD TAP..1
R 2
(-5950 5075);
FORCEPROP 3 LASTPIN (-5900 5075) SIG_NAME M_D_CPU1_SA_DQS_DN<9>
J 0
(-5890 5085);
DISPLAY 0.659574 (-5890 5085);
PAINT MONO (-5890 5085);
DISPLAY INVISIBLE (-5890 5085);
FORCEPROP 1 LASTPIN (-5900 5075) BN 9
J 2
(-5888 5083);
DISPLAY 0.489362 (-5888 5083);
PAINT GREEN (-5888 5083);
FORCEPROP 2 LAST CDS_LIB mstr_standard
J 2
(-5950 5075);
DISPLAY 0.723404 (-5950 5075);
PAINT MONO (-5950 5075);
DISPLAY INVISIBLE (-5950 5075);
FORCEPROP 1 LAST BODY_TYPE PLUMBING
J 2
(-5950 5125);
DISPLAY 0.872340 (-5950 5125);
PAINT GREEN (-5950 5125);
DISPLAY INVISIBLE (-5950 5125);
FORCEPROP 1 LAST HDL_TAP TRUE
J 2
(-6275 4950);
DISPLAY 0.872340 (-6275 4950);
DISPLAY INVISIBLE (-6275 4950);
FORCEPROP 1 LAST PATH I267
J 2
(-5948 5075);
DISPLAY 0.872340 (-5948 5075);
PAINT GREEN (-5948 5075);
DISPLAY INVISIBLE (-5948 5075);
FORCEADD TAP..1
R 2
(-5950 4925);
FORCEPROP 3 LASTPIN (-5900 4925) SIG_NAME M_D_CPU1_SB_DQS_DN<0>
J 0
(-5890 4935);
DISPLAY 0.659574 (-5890 4935);
PAINT MONO (-5890 4935);
DISPLAY INVISIBLE (-5890 4935);
FORCEPROP 1 LASTPIN (-5900 4925) BN 0
J 2
(-5888 4933);
DISPLAY 0.489362 (-5888 4933);
PAINT GREEN (-5888 4933);
FORCEPROP 2 LAST CDS_LIB mstr_standard
J 2
(-5950 4925);
DISPLAY 0.723404 (-5950 4925);
PAINT MONO (-5950 4925);
DISPLAY INVISIBLE (-5950 4925);
FORCEPROP 1 LAST BODY_TYPE PLUMBING
J 2
(-5950 4975);
DISPLAY 0.872340 (-5950 4975);
PAINT GREEN (-5950 4975);
DISPLAY INVISIBLE (-5950 4975);
FORCEPROP 1 LAST HDL_TAP TRUE
J 2
(-6275 4800);
DISPLAY 0.872340 (-6275 4800);
DISPLAY INVISIBLE (-6275 4800);
FORCEPROP 1 LAST PATH I268
J 2
(-5948 4925);
DISPLAY 0.872340 (-5948 4925);
PAINT GREEN (-5948 4925);
DISPLAY INVISIBLE (-5948 4925);
FORCEADD TAP..1
R 2
(-5950 4825);
FORCEPROP 3 LASTPIN (-5900 4825) SIG_NAME M_D_CPU1_SB_DQS_DN<1>
J 0
(-5890 4835);
DISPLAY 0.659574 (-5890 4835);
PAINT MONO (-5890 4835);
DISPLAY INVISIBLE (-5890 4835);
FORCEPROP 1 LASTPIN (-5900 4825) BN 1
J 2
(-5888 4833);
DISPLAY 0.489362 (-5888 4833);
PAINT GREEN (-5888 4833);
FORCEPROP 2 LAST CDS_LIB mstr_standard
J 2
(-5950 4825);
DISPLAY 0.723404 (-5950 4825);
PAINT MONO (-5950 4825);
DISPLAY INVISIBLE (-5950 4825);
FORCEPROP 1 LAST BODY_TYPE PLUMBING
J 2
(-5950 4875);
DISPLAY 0.872340 (-5950 4875);
PAINT GREEN (-5950 4875);
DISPLAY INVISIBLE (-5950 4875);
FORCEPROP 1 LAST HDL_TAP TRUE
J 2
(-6275 4700);
DISPLAY 0.872340 (-6275 4700);
DISPLAY INVISIBLE (-6275 4700);
FORCEPROP 1 LAST PATH I269
J 2
(-5948 4825);
DISPLAY 0.872340 (-5948 4825);
PAINT GREEN (-5948 4825);
DISPLAY INVISIBLE (-5948 4825);
FORCEADD TAP..1
R 2
(-5950 4725);
FORCEPROP 3 LASTPIN (-5900 4725) SIG_NAME M_D_CPU1_SB_DQS_DN<2>
J 0
(-5890 4735);
DISPLAY 0.659574 (-5890 4735);
PAINT MONO (-5890 4735);
DISPLAY INVISIBLE (-5890 4735);
FORCEPROP 1 LASTPIN (-5900 4725) BN 2
J 2
(-5888 4733);
DISPLAY 0.489362 (-5888 4733);
PAINT GREEN (-5888 4733);
FORCEPROP 2 LAST CDS_LIB mstr_standard
J 2
(-5950 4725);
DISPLAY 0.723404 (-5950 4725);
PAINT MONO (-5950 4725);
DISPLAY INVISIBLE (-5950 4725);
FORCEPROP 1 LAST BODY_TYPE PLUMBING
J 2
(-5950 4775);
DISPLAY 0.872340 (-5950 4775);
PAINT GREEN (-5950 4775);
DISPLAY INVISIBLE (-5950 4775);
FORCEPROP 1 LAST HDL_TAP TRUE
J 2
(-6275 4600);
DISPLAY 0.872340 (-6275 4600);
DISPLAY INVISIBLE (-6275 4600);
FORCEPROP 1 LAST PATH I270
J 2
(-5948 4725);
DISPLAY 0.872340 (-5948 4725);
PAINT GREEN (-5948 4725);
DISPLAY INVISIBLE (-5948 4725);
FORCEADD TAP..1
R 2
(-5950 4625);
FORCEPROP 3 LASTPIN (-5900 4625) SIG_NAME M_D_CPU1_SB_DQS_DN<3>
J 0
(-5890 4635);
DISPLAY 0.659574 (-5890 4635);
PAINT MONO (-5890 4635);
DISPLAY INVISIBLE (-5890 4635);
FORCEPROP 1 LASTPIN (-5900 4625) BN 3
J 2
(-5888 4633);
DISPLAY 0.489362 (-5888 4633);
PAINT GREEN (-5888 4633);
FORCEPROP 2 LAST CDS_LIB mstr_standard
J 2
(-5950 4625);
DISPLAY 0.723404 (-5950 4625);
PAINT MONO (-5950 4625);
DISPLAY INVISIBLE (-5950 4625);
FORCEPROP 1 LAST BODY_TYPE PLUMBING
J 2
(-5950 4675);
DISPLAY 0.872340 (-5950 4675);
PAINT GREEN (-5950 4675);
DISPLAY INVISIBLE (-5950 4675);
FORCEPROP 1 LAST HDL_TAP TRUE
J 2
(-6275 4500);
DISPLAY 0.872340 (-6275 4500);
DISPLAY INVISIBLE (-6275 4500);
FORCEPROP 1 LAST PATH I271
J 2
(-5948 4625);
DISPLAY 0.872340 (-5948 4625);
PAINT GREEN (-5948 4625);
DISPLAY INVISIBLE (-5948 4625);
FORCEADD TAP..1
R 2
(-5750 4575);
FORCEPROP 3 LASTPIN (-5700 4575) SIG_NAME M_D_CPU1_SB_DQS_DP<4>
J 0
(-5690 4585);
DISPLAY 0.659574 (-5690 4585);
PAINT MONO (-5690 4585);
DISPLAY INVISIBLE (-5690 4585);
FORCEPROP 1 LASTPIN (-5700 4575) BN 4
J 2
(-5688 4583);
DISPLAY 0.489362 (-5688 4583);
PAINT GREEN (-5688 4583);
FORCEPROP 2 LAST CDS_LIB mstr_standard
J 2
(-5750 4575);
DISPLAY 0.723404 (-5750 4575);
PAINT MONO (-5750 4575);
DISPLAY INVISIBLE (-5750 4575);
FORCEPROP 1 LAST BODY_TYPE PLUMBING
J 2
(-5750 4625);
DISPLAY 0.872340 (-5750 4625);
PAINT GREEN (-5750 4625);
DISPLAY INVISIBLE (-5750 4625);
FORCEPROP 1 LAST HDL_TAP TRUE
J 2
(-6075 4450);
DISPLAY 0.872340 (-6075 4450);
DISPLAY INVISIBLE (-6075 4450);
FORCEPROP 1 LAST PATH I272
J 2
(-5748 4575);
DISPLAY 0.872340 (-5748 4575);
PAINT GREEN (-5748 4575);
DISPLAY INVISIBLE (-5748 4575);
FORCEADD TAP..1
R 2
(-5750 4475);
FORCEPROP 3 LASTPIN (-5700 4475) SIG_NAME M_D_CPU1_SB_DQS_DP<5>
J 0
(-5690 4485);
DISPLAY 0.659574 (-5690 4485);
PAINT MONO (-5690 4485);
DISPLAY INVISIBLE (-5690 4485);
FORCEPROP 1 LASTPIN (-5700 4475) BN 5
J 2
(-5688 4483);
DISPLAY 0.489362 (-5688 4483);
PAINT GREEN (-5688 4483);
FORCEPROP 2 LAST CDS_LIB mstr_standard
J 2
(-5750 4475);
DISPLAY 0.723404 (-5750 4475);
PAINT MONO (-5750 4475);
DISPLAY INVISIBLE (-5750 4475);
FORCEPROP 1 LAST BODY_TYPE PLUMBING
J 2
(-5750 4525);
DISPLAY 0.872340 (-5750 4525);
PAINT GREEN (-5750 4525);
DISPLAY INVISIBLE (-5750 4525);
FORCEPROP 1 LAST HDL_TAP TRUE
J 2
(-6075 4350);
DISPLAY 0.872340 (-6075 4350);
DISPLAY INVISIBLE (-6075 4350);
FORCEPROP 1 LAST PATH I273
J 2
(-5748 4475);
DISPLAY 0.872340 (-5748 4475);
PAINT GREEN (-5748 4475);
DISPLAY INVISIBLE (-5748 4475);
FORCEADD TAP..1
R 2
(-5750 4375);
FORCEPROP 3 LASTPIN (-5700 4375) SIG_NAME M_D_CPU1_SB_DQS_DP<6>
J 0
(-5690 4385);
DISPLAY 0.659574 (-5690 4385);
PAINT MONO (-5690 4385);
DISPLAY INVISIBLE (-5690 4385);
FORCEPROP 1 LASTPIN (-5700 4375) BN 6
J 2
(-5688 4383);
DISPLAY 0.489362 (-5688 4383);
PAINT GREEN (-5688 4383);
FORCEPROP 2 LAST CDS_LIB mstr_standard
J 2
(-5750 4375);
DISPLAY 0.723404 (-5750 4375);
PAINT MONO (-5750 4375);
DISPLAY INVISIBLE (-5750 4375);
FORCEPROP 1 LAST BODY_TYPE PLUMBING
J 2
(-5750 4425);
DISPLAY 0.872340 (-5750 4425);
PAINT GREEN (-5750 4425);
DISPLAY INVISIBLE (-5750 4425);
FORCEPROP 1 LAST HDL_TAP TRUE
J 2
(-6075 4250);
DISPLAY 0.872340 (-6075 4250);
DISPLAY INVISIBLE (-6075 4250);
FORCEPROP 1 LAST PATH I274
J 2
(-5748 4375);
DISPLAY 0.872340 (-5748 4375);
PAINT GREEN (-5748 4375);
DISPLAY INVISIBLE (-5748 4375);
FORCEADD TAP..1
R 2
(-5750 4275);
FORCEPROP 3 LASTPIN (-5700 4275) SIG_NAME M_D_CPU1_SB_DQS_DP<7>
J 0
(-5690 4285);
DISPLAY 0.659574 (-5690 4285);
PAINT MONO (-5690 4285);
DISPLAY INVISIBLE (-5690 4285);
FORCEPROP 1 LASTPIN (-5700 4275) BN 7
J 2
(-5688 4283);
DISPLAY 0.489362 (-5688 4283);
PAINT GREEN (-5688 4283);
FORCEPROP 2 LAST CDS_LIB mstr_standard
J 2
(-5750 4275);
DISPLAY 0.723404 (-5750 4275);
PAINT MONO (-5750 4275);
DISPLAY INVISIBLE (-5750 4275);
FORCEPROP 1 LAST BODY_TYPE PLUMBING
J 2
(-5750 4325);
DISPLAY 0.872340 (-5750 4325);
PAINT GREEN (-5750 4325);
DISPLAY INVISIBLE (-5750 4325);
FORCEPROP 1 LAST HDL_TAP TRUE
J 2
(-6075 4150);
DISPLAY 0.872340 (-6075 4150);
DISPLAY INVISIBLE (-6075 4150);
FORCEPROP 1 LAST PATH I275
J 2
(-5748 4275);
DISPLAY 0.872340 (-5748 4275);
PAINT GREEN (-5748 4275);
DISPLAY INVISIBLE (-5748 4275);
FORCEADD TAP..1
R 2
(-5750 4175);
FORCEPROP 3 LASTPIN (-5700 4175) SIG_NAME M_D_CPU1_SB_DQS_DP<8>
J 0
(-5690 4185);
DISPLAY 0.659574 (-5690 4185);
PAINT MONO (-5690 4185);
DISPLAY INVISIBLE (-5690 4185);
FORCEPROP 1 LASTPIN (-5700 4175) BN 8
J 2
(-5688 4183);
DISPLAY 0.489362 (-5688 4183);
PAINT GREEN (-5688 4183);
FORCEPROP 2 LAST CDS_LIB mstr_standard
J 2
(-5750 4175);
DISPLAY 0.723404 (-5750 4175);
PAINT MONO (-5750 4175);
DISPLAY INVISIBLE (-5750 4175);
FORCEPROP 1 LAST BODY_TYPE PLUMBING
J 2
(-5750 4225);
DISPLAY 0.872340 (-5750 4225);
PAINT GREEN (-5750 4225);
DISPLAY INVISIBLE (-5750 4225);
FORCEPROP 1 LAST HDL_TAP TRUE
J 2
(-6075 4050);
DISPLAY 0.872340 (-6075 4050);
DISPLAY INVISIBLE (-6075 4050);
FORCEPROP 1 LAST PATH I276
J 2
(-5748 4175);
DISPLAY 0.872340 (-5748 4175);
PAINT GREEN (-5748 4175);
DISPLAY INVISIBLE (-5748 4175);
FORCEADD TAP..1
R 2
(-5950 4525);
FORCEPROP 3 LASTPIN (-5900 4525) SIG_NAME M_D_CPU1_SB_DQS_DN<4>
J 0
(-5890 4535);
DISPLAY 0.659574 (-5890 4535);
PAINT MONO (-5890 4535);
DISPLAY INVISIBLE (-5890 4535);
FORCEPROP 1 LASTPIN (-5900 4525) BN 4
J 2
(-5888 4533);
DISPLAY 0.489362 (-5888 4533);
PAINT GREEN (-5888 4533);
FORCEPROP 2 LAST CDS_LIB mstr_standard
J 2
(-5950 4525);
DISPLAY 0.723404 (-5950 4525);
PAINT MONO (-5950 4525);
DISPLAY INVISIBLE (-5950 4525);
FORCEPROP 1 LAST BODY_TYPE PLUMBING
J 2
(-5950 4575);
DISPLAY 0.872340 (-5950 4575);
PAINT GREEN (-5950 4575);
DISPLAY INVISIBLE (-5950 4575);
FORCEPROP 1 LAST HDL_TAP TRUE
J 2
(-6275 4400);
DISPLAY 0.872340 (-6275 4400);
DISPLAY INVISIBLE (-6275 4400);
FORCEPROP 1 LAST PATH I277
J 2
(-5948 4525);
DISPLAY 0.872340 (-5948 4525);
PAINT GREEN (-5948 4525);
DISPLAY INVISIBLE (-5948 4525);
FORCEADD TAP..1
R 2
(-5950 4425);
FORCEPROP 3 LASTPIN (-5900 4425) SIG_NAME M_D_CPU1_SB_DQS_DN<5>
J 0
(-5890 4435);
DISPLAY 0.659574 (-5890 4435);
PAINT MONO (-5890 4435);
DISPLAY INVISIBLE (-5890 4435);
FORCEPROP 1 LASTPIN (-5900 4425) BN 5
J 2
(-5888 4433);
DISPLAY 0.489362 (-5888 4433);
PAINT GREEN (-5888 4433);
FORCEPROP 2 LAST CDS_LIB mstr_standard
J 2
(-5950 4425);
DISPLAY 0.723404 (-5950 4425);
PAINT MONO (-5950 4425);
DISPLAY INVISIBLE (-5950 4425);
FORCEPROP 1 LAST BODY_TYPE PLUMBING
J 2
(-5950 4475);
DISPLAY 0.872340 (-5950 4475);
PAINT GREEN (-5950 4475);
DISPLAY INVISIBLE (-5950 4475);
FORCEPROP 1 LAST HDL_TAP TRUE
J 2
(-6275 4300);
DISPLAY 0.872340 (-6275 4300);
DISPLAY INVISIBLE (-6275 4300);
FORCEPROP 1 LAST PATH I278
J 2
(-5948 4425);
DISPLAY 0.872340 (-5948 4425);
PAINT GREEN (-5948 4425);
DISPLAY INVISIBLE (-5948 4425);
FORCEADD TAP..1
R 2
(-5950 4325);
FORCEPROP 3 LASTPIN (-5900 4325) SIG_NAME M_D_CPU1_SB_DQS_DN<6>
J 0
(-5890 4335);
DISPLAY 0.659574 (-5890 4335);
PAINT MONO (-5890 4335);
DISPLAY INVISIBLE (-5890 4335);
FORCEPROP 1 LASTPIN (-5900 4325) BN 6
J 2
(-5888 4333);
DISPLAY 0.489362 (-5888 4333);
PAINT GREEN (-5888 4333);
FORCEPROP 2 LAST CDS_LIB mstr_standard
J 2
(-5950 4325);
DISPLAY 0.723404 (-5950 4325);
PAINT MONO (-5950 4325);
DISPLAY INVISIBLE (-5950 4325);
FORCEPROP 1 LAST BODY_TYPE PLUMBING
J 2
(-5950 4375);
DISPLAY 0.872340 (-5950 4375);
PAINT GREEN (-5950 4375);
DISPLAY INVISIBLE (-5950 4375);
FORCEPROP 1 LAST HDL_TAP TRUE
J 2
(-6275 4200);
DISPLAY 0.872340 (-6275 4200);
DISPLAY INVISIBLE (-6275 4200);
FORCEPROP 1 LAST PATH I279
J 2
(-5948 4325);
DISPLAY 0.872340 (-5948 4325);
PAINT GREEN (-5948 4325);
DISPLAY INVISIBLE (-5948 4325);
FORCEADD TAP..1
R 2
(-5950 4225);
FORCEPROP 3 LASTPIN (-5900 4225) SIG_NAME M_D_CPU1_SB_DQS_DN<7>
J 0
(-5890 4235);
DISPLAY 0.659574 (-5890 4235);
PAINT MONO (-5890 4235);
DISPLAY INVISIBLE (-5890 4235);
FORCEPROP 1 LASTPIN (-5900 4225) BN 7
J 2
(-5888 4233);
DISPLAY 0.489362 (-5888 4233);
PAINT GREEN (-5888 4233);
FORCEPROP 2 LAST CDS_LIB mstr_standard
J 2
(-5950 4225);
DISPLAY 0.723404 (-5950 4225);
PAINT MONO (-5950 4225);
DISPLAY INVISIBLE (-5950 4225);
FORCEPROP 1 LAST BODY_TYPE PLUMBING
J 2
(-5950 4275);
DISPLAY 0.872340 (-5950 4275);
PAINT GREEN (-5950 4275);
DISPLAY INVISIBLE (-5950 4275);
FORCEPROP 1 LAST HDL_TAP TRUE
J 2
(-6275 4100);
DISPLAY 0.872340 (-6275 4100);
DISPLAY INVISIBLE (-6275 4100);
FORCEPROP 1 LAST PATH I280
J 2
(-5948 4225);
DISPLAY 0.872340 (-5948 4225);
PAINT GREEN (-5948 4225);
DISPLAY INVISIBLE (-5948 4225);
FORCEADD TAP..1
R 2
(-5950 4125);
FORCEPROP 3 LASTPIN (-5900 4125) SIG_NAME M_D_CPU1_SB_DQS_DN<8>
J 0
(-5890 4135);
DISPLAY 0.659574 (-5890 4135);
PAINT MONO (-5890 4135);
DISPLAY INVISIBLE (-5890 4135);
FORCEPROP 1 LASTPIN (-5900 4125) BN 8
J 2
(-5888 4133);
DISPLAY 0.489362 (-5888 4133);
PAINT GREEN (-5888 4133);
FORCEPROP 2 LAST CDS_LIB mstr_standard
J 2
(-5950 4125);
DISPLAY 0.723404 (-5950 4125);
PAINT MONO (-5950 4125);
DISPLAY INVISIBLE (-5950 4125);
FORCEPROP 1 LAST BODY_TYPE PLUMBING
J 2
(-5950 4175);
DISPLAY 0.872340 (-5950 4175);
PAINT GREEN (-5950 4175);
DISPLAY INVISIBLE (-5950 4175);
FORCEPROP 1 LAST HDL_TAP TRUE
J 2
(-6275 4000);
DISPLAY 0.872340 (-6275 4000);
DISPLAY INVISIBLE (-6275 4000);
FORCEPROP 1 LAST PATH I281
J 2
(-5948 4125);
DISPLAY 0.872340 (-5948 4125);
PAINT GREEN (-5948 4125);
DISPLAY INVISIBLE (-5948 4125);
FORCEADD OFFPAGE..3
R 2
(-6650 6050);
FORCEPROP 2 LAST $XR0 101 
J 0
(-6930 6050);
DISPLAY 0.638298 (-6930 6050);
PAINT MONO (-6930 6050);
FORCEPROP 2 LAST CDS_LIB standard
J 0
(-6650 6050);
DISPLAY INVISIBLE (-6650 6050);
FORCEPROP 1 LAST OFFPAGE TRUE
J 2
(-6975 5925);
DISPLAY 0.872340 (-6975 5925);
PAINT GREEN (-6975 5925);
DISPLAY INVISIBLE (-6975 5925);
FORCEPROP 1 LAST COMMENT_BODY TRUE
J 2
(-6600 5950);
DISPLAY 0.872340 (-6600 5950);
PAINT GREEN (-6600 5950);
DISPLAY INVISIBLE (-6600 5950);
FORCEPROP 2 LAST PATH I282
J 0
(-6925 6100);
DISPLAY 1.021277 (-6925 6100);
DISPLAY INVISIBLE (-6925 6100);
FORCEADD OFFPAGE..3
R 2
(-6650 6000);
FORCEPROP 2 LAST $XR0 101 
J 0
(-6930 6000);
DISPLAY 0.638298 (-6930 6000);
PAINT MONO (-6930 6000);
FORCEPROP 2 LAST CDS_LIB standard
J 0
(-6650 6000);
DISPLAY INVISIBLE (-6650 6000);
FORCEPROP 1 LAST OFFPAGE TRUE
J 2
(-6975 5875);
DISPLAY 0.872340 (-6975 5875);
PAINT GREEN (-6975 5875);
DISPLAY INVISIBLE (-6975 5875);
FORCEPROP 1 LAST COMMENT_BODY TRUE
J 2
(-6600 5900);
DISPLAY 0.872340 (-6600 5900);
PAINT GREEN (-6600 5900);
DISPLAY INVISIBLE (-6600 5900);
FORCEPROP 2 LAST PATH I283
J 0
(-6925 6050);
DISPLAY 1.021277 (-6925 6050);
DISPLAY INVISIBLE (-6925 6050);
FORCEADD OFFPAGE..3
R 2
(-6650 5000);
FORCEPROP 2 LAST $XR0 101 
J 0
(-6930 5000);
DISPLAY 0.638298 (-6930 5000);
PAINT MONO (-6930 5000);
FORCEPROP 2 LAST CDS_LIB standard
J 0
(-6650 5000);
DISPLAY INVISIBLE (-6650 5000);
FORCEPROP 1 LAST OFFPAGE TRUE
J 2
(-6975 4875);
DISPLAY 0.872340 (-6975 4875);
PAINT GREEN (-6975 4875);
DISPLAY INVISIBLE (-6975 4875);
FORCEPROP 1 LAST COMMENT_BODY TRUE
J 2
(-6600 4900);
DISPLAY 0.872340 (-6600 4900);
PAINT GREEN (-6600 4900);
DISPLAY INVISIBLE (-6600 4900);
FORCEPROP 2 LAST PATH I284
J 0
(-6925 5050);
DISPLAY 1.021277 (-6925 5050);
DISPLAY INVISIBLE (-6925 5050);
FORCEADD OFFPAGE..3
R 2
(-6650 4950);
FORCEPROP 2 LAST $XR0 101 
J 0
(-6930 4950);
DISPLAY 0.638298 (-6930 4950);
PAINT MONO (-6930 4950);
FORCEPROP 2 LAST CDS_LIB standard
J 0
(-6650 4950);
DISPLAY INVISIBLE (-6650 4950);
FORCEPROP 1 LAST OFFPAGE TRUE
J 2
(-6975 4825);
DISPLAY 0.872340 (-6975 4825);
PAINT GREEN (-6975 4825);
DISPLAY INVISIBLE (-6975 4825);
FORCEPROP 1 LAST COMMENT_BODY TRUE
J 2
(-6600 4850);
DISPLAY 0.872340 (-6600 4850);
PAINT GREEN (-6600 4850);
DISPLAY INVISIBLE (-6600 4850);
FORCEPROP 2 LAST PATH I285
J 0
(-6925 5000);
DISPLAY 1.021277 (-6925 5000);
DISPLAY INVISIBLE (-6925 5000);
FORCEADD TAP..1
R 2
(-5750 4075);
FORCEPROP 3 LASTPIN (-5700 4075) SIG_NAME M_D_CPU1_SB_DQS_DP<9>
J 0
(-5690 4085);
DISPLAY 0.659574 (-5690 4085);
PAINT MONO (-5690 4085);
DISPLAY INVISIBLE (-5690 4085);
FORCEPROP 1 LASTPIN (-5700 4075) BN 9
J 2
(-5688 4083);
DISPLAY 0.489362 (-5688 4083);
PAINT GREEN (-5688 4083);
FORCEPROP 2 LAST CDS_LIB mstr_standard
J 2
(-5750 4075);
DISPLAY 0.723404 (-5750 4075);
PAINT MONO (-5750 4075);
DISPLAY INVISIBLE (-5750 4075);
FORCEPROP 1 LAST BODY_TYPE PLUMBING
J 2
(-5750 4125);
DISPLAY 0.872340 (-5750 4125);
PAINT GREEN (-5750 4125);
DISPLAY INVISIBLE (-5750 4125);
FORCEPROP 1 LAST HDL_TAP TRUE
J 2
(-6075 3950);
DISPLAY 0.872340 (-6075 3950);
DISPLAY INVISIBLE (-6075 3950);
FORCEPROP 1 LAST PATH I286
J 2
(-5748 4075);
DISPLAY 0.872340 (-5748 4075);
PAINT GREEN (-5748 4075);
DISPLAY INVISIBLE (-5748 4075);
FORCEADD TAP..1
R 2
(-5950 4025);
FORCEPROP 3 LASTPIN (-5900 4025) SIG_NAME M_D_CPU1_SB_DQS_DN<9>
J 0
(-5890 4035);
DISPLAY 0.659574 (-5890 4035);
PAINT MONO (-5890 4035);
DISPLAY INVISIBLE (-5890 4035);
FORCEPROP 1 LASTPIN (-5900 4025) BN 9
J 2
(-5888 4033);
DISPLAY 0.489362 (-5888 4033);
PAINT GREEN (-5888 4033);
FORCEPROP 2 LAST CDS_LIB mstr_standard
J 2
(-5950 4025);
DISPLAY 0.723404 (-5950 4025);
PAINT MONO (-5950 4025);
DISPLAY INVISIBLE (-5950 4025);
FORCEPROP 1 LAST BODY_TYPE PLUMBING
J 2
(-5950 4075);
DISPLAY 0.872340 (-5950 4075);
PAINT GREEN (-5950 4075);
DISPLAY INVISIBLE (-5950 4075);
FORCEPROP 1 LAST HDL_TAP TRUE
J 2
(-6275 3900);
DISPLAY 0.872340 (-6275 3900);
DISPLAY INVISIBLE (-6275 3900);
FORCEPROP 1 LAST PATH I287
J 2
(-5948 4025);
DISPLAY 0.872340 (-5948 4025);
PAINT GREEN (-5948 4025);
DISPLAY INVISIBLE (-5948 4025);
FORCEADD TAP..1
R 2
(-5950 3825);
FORCEPROP 3 LASTPIN (-5900 3825) SIG_NAME M_D_CPU1_SA_CA<1>
J 0
(-5890 3835);
DISPLAY 0.659574 (-5890 3835);
PAINT MONO (-5890 3835);
DISPLAY INVISIBLE (-5890 3835);
FORCEPROP 1 LASTPIN (-5900 3825) BN 1
J 2
(-5888 3833);
DISPLAY 0.489362 (-5888 3833);
PAINT GREEN (-5888 3833);
FORCEPROP 2 LAST CDS_LIB mstr_standard
J 0
(-5950 3825);
DISPLAY 0.723404 (-5950 3825);
PAINT MONO (-5950 3825);
DISPLAY INVISIBLE (-5950 3825);
FORCEPROP 1 LAST BODY_TYPE PLUMBING
J 2
(-5950 3875);
DISPLAY 0.872340 (-5950 3875);
PAINT GREEN (-5950 3875);
DISPLAY INVISIBLE (-5950 3875);
FORCEPROP 1 LAST HDL_TAP TRUE
J 2
(-6275 3700);
DISPLAY 0.872340 (-6275 3700);
DISPLAY INVISIBLE (-6275 3700);
FORCEPROP 1 LAST PATH I288
J 2
(-5948 3825);
DISPLAY 0.872340 (-5948 3825);
PAINT GREEN (-5948 3825);
DISPLAY INVISIBLE (-5948 3825);
FORCEADD TAP..1
R 2
(-5950 3875);
FORCEPROP 3 LASTPIN (-5900 3875) SIG_NAME M_D_CPU1_SA_CA<0>
J 0
(-5890 3885);
DISPLAY 0.659574 (-5890 3885);
PAINT MONO (-5890 3885);
DISPLAY INVISIBLE (-5890 3885);
FORCEPROP 1 LASTPIN (-5900 3875) BN 0
J 2
(-5888 3883);
DISPLAY 0.489362 (-5888 3883);
PAINT GREEN (-5888 3883);
FORCEPROP 2 LAST CDS_LIB mstr_standard
J 0
(-5950 3875);
DISPLAY 0.723404 (-5950 3875);
PAINT MONO (-5950 3875);
DISPLAY INVISIBLE (-5950 3875);
FORCEPROP 1 LAST BODY_TYPE PLUMBING
J 2
(-5950 3925);
DISPLAY 0.872340 (-5950 3925);
PAINT GREEN (-5950 3925);
DISPLAY INVISIBLE (-5950 3925);
FORCEPROP 1 LAST HDL_TAP TRUE
J 2
(-6275 3750);
DISPLAY 0.872340 (-6275 3750);
DISPLAY INVISIBLE (-6275 3750);
FORCEPROP 1 LAST PATH I289
J 2
(-5948 3875);
DISPLAY 0.872340 (-5948 3875);
PAINT GREEN (-5948 3875);
DISPLAY INVISIBLE (-5948 3875);
FORCEADD TAP..1
R 2
(-5950 3775);
FORCEPROP 3 LASTPIN (-5900 3775) SIG_NAME M_D_CPU1_SA_CA<2>
J 0
(-5890 3785);
DISPLAY 0.659574 (-5890 3785);
PAINT MONO (-5890 3785);
DISPLAY INVISIBLE (-5890 3785);
FORCEPROP 1 LASTPIN (-5900 3775) BN 2
J 2
(-5888 3783);
DISPLAY 0.489362 (-5888 3783);
PAINT GREEN (-5888 3783);
FORCEPROP 2 LAST CDS_LIB mstr_standard
J 0
(-5950 3775);
DISPLAY 0.723404 (-5950 3775);
PAINT MONO (-5950 3775);
DISPLAY INVISIBLE (-5950 3775);
FORCEPROP 1 LAST BODY_TYPE PLUMBING
J 2
(-5950 3825);
DISPLAY 0.872340 (-5950 3825);
PAINT GREEN (-5950 3825);
DISPLAY INVISIBLE (-5950 3825);
FORCEPROP 1 LAST HDL_TAP TRUE
J 2
(-6275 3650);
DISPLAY 0.872340 (-6275 3650);
DISPLAY INVISIBLE (-6275 3650);
FORCEPROP 1 LAST PATH I290
J 2
(-5948 3775);
DISPLAY 0.872340 (-5948 3775);
PAINT GREEN (-5948 3775);
DISPLAY INVISIBLE (-5948 3775);
FORCEADD TAP..1
R 2
(-5950 3725);
FORCEPROP 3 LASTPIN (-5900 3725) SIG_NAME M_D_CPU1_SA_CA<3>
J 0
(-5890 3735);
DISPLAY 0.659574 (-5890 3735);
PAINT MONO (-5890 3735);
DISPLAY INVISIBLE (-5890 3735);
FORCEPROP 1 LASTPIN (-5900 3725) BN 3
J 2
(-5888 3733);
DISPLAY 0.489362 (-5888 3733);
PAINT GREEN (-5888 3733);
FORCEPROP 2 LAST CDS_LIB mstr_standard
J 0
(-5950 3725);
DISPLAY 0.723404 (-5950 3725);
PAINT MONO (-5950 3725);
DISPLAY INVISIBLE (-5950 3725);
FORCEPROP 1 LAST BODY_TYPE PLUMBING
J 2
(-5950 3775);
DISPLAY 0.872340 (-5950 3775);
PAINT GREEN (-5950 3775);
DISPLAY INVISIBLE (-5950 3775);
FORCEPROP 1 LAST HDL_TAP TRUE
J 2
(-6275 3600);
DISPLAY 0.872340 (-6275 3600);
DISPLAY INVISIBLE (-6275 3600);
FORCEPROP 1 LAST PATH I291
J 2
(-5948 3725);
DISPLAY 0.872340 (-5948 3725);
PAINT GREEN (-5948 3725);
DISPLAY INVISIBLE (-5948 3725);
FORCEADD TAP..1
R 2
(-5950 3675);
FORCEPROP 3 LASTPIN (-5900 3675) SIG_NAME M_D_CPU1_SA_CA<4>
J 0
(-5890 3685);
DISPLAY 0.659574 (-5890 3685);
PAINT MONO (-5890 3685);
DISPLAY INVISIBLE (-5890 3685);
FORCEPROP 1 LASTPIN (-5900 3675) BN 4
J 2
(-5888 3683);
DISPLAY 0.489362 (-5888 3683);
PAINT GREEN (-5888 3683);
FORCEPROP 2 LAST CDS_LIB mstr_standard
J 0
(-5950 3675);
DISPLAY 0.723404 (-5950 3675);
PAINT MONO (-5950 3675);
DISPLAY INVISIBLE (-5950 3675);
FORCEPROP 1 LAST BODY_TYPE PLUMBING
J 2
(-5950 3725);
DISPLAY 0.872340 (-5950 3725);
PAINT GREEN (-5950 3725);
DISPLAY INVISIBLE (-5950 3725);
FORCEPROP 1 LAST HDL_TAP TRUE
J 2
(-6275 3550);
DISPLAY 0.872340 (-6275 3550);
DISPLAY INVISIBLE (-6275 3550);
FORCEPROP 1 LAST PATH I292
J 2
(-5948 3675);
DISPLAY 0.872340 (-5948 3675);
PAINT GREEN (-5948 3675);
DISPLAY INVISIBLE (-5948 3675);
FORCEADD TAP..1
R 2
(-5950 3625);
FORCEPROP 3 LASTPIN (-5900 3625) SIG_NAME M_D_CPU1_SA_CA<5>
J 0
(-5890 3635);
DISPLAY 0.659574 (-5890 3635);
PAINT MONO (-5890 3635);
DISPLAY INVISIBLE (-5890 3635);
FORCEPROP 1 LASTPIN (-5900 3625) BN 5
J 2
(-5888 3633);
DISPLAY 0.489362 (-5888 3633);
PAINT GREEN (-5888 3633);
FORCEPROP 2 LAST CDS_LIB mstr_standard
J 0
(-5950 3625);
DISPLAY 0.723404 (-5950 3625);
PAINT MONO (-5950 3625);
DISPLAY INVISIBLE (-5950 3625);
FORCEPROP 1 LAST BODY_TYPE PLUMBING
J 2
(-5950 3675);
DISPLAY 0.872340 (-5950 3675);
PAINT GREEN (-5950 3675);
DISPLAY INVISIBLE (-5950 3675);
FORCEPROP 1 LAST HDL_TAP TRUE
J 2
(-6275 3500);
DISPLAY 0.872340 (-6275 3500);
DISPLAY INVISIBLE (-6275 3500);
FORCEPROP 1 LAST PATH I293
J 2
(-5948 3625);
DISPLAY 0.872340 (-5948 3625);
PAINT GREEN (-5948 3625);
DISPLAY INVISIBLE (-5948 3625);
FORCEADD TAP..1
R 2
(-5950 3575);
FORCEPROP 3 LASTPIN (-5900 3575) SIG_NAME M_D_CPU1_SA_CA<6>
J 0
(-5890 3585);
DISPLAY 0.659574 (-5890 3585);
PAINT MONO (-5890 3585);
DISPLAY INVISIBLE (-5890 3585);
FORCEPROP 1 LASTPIN (-5900 3575) BN 6
J 2
(-5888 3583);
DISPLAY 0.489362 (-5888 3583);
PAINT GREEN (-5888 3583);
FORCEPROP 2 LAST CDS_LIB mstr_standard
J 0
(-5950 3575);
DISPLAY 0.723404 (-5950 3575);
PAINT MONO (-5950 3575);
DISPLAY INVISIBLE (-5950 3575);
FORCEPROP 1 LAST BODY_TYPE PLUMBING
J 2
(-5950 3625);
DISPLAY 0.872340 (-5950 3625);
PAINT GREEN (-5950 3625);
DISPLAY INVISIBLE (-5950 3625);
FORCEPROP 1 LAST HDL_TAP TRUE
J 2
(-6275 3450);
DISPLAY 0.872340 (-6275 3450);
DISPLAY INVISIBLE (-6275 3450);
FORCEPROP 1 LAST PATH I294
J 2
(-5948 3575);
DISPLAY 0.872340 (-5948 3575);
PAINT GREEN (-5948 3575);
DISPLAY INVISIBLE (-5948 3575);
FORCEADD TAP..1
R 2
(-5950 3425);
FORCEPROP 3 LASTPIN (-5900 3425) SIG_NAME M_D_CPU1_SB_CA<1>
J 0
(-5890 3435);
DISPLAY 0.659574 (-5890 3435);
PAINT MONO (-5890 3435);
DISPLAY INVISIBLE (-5890 3435);
FORCEPROP 1 LASTPIN (-5900 3425) BN 1
J 2
(-5888 3433);
DISPLAY 0.489362 (-5888 3433);
PAINT GREEN (-5888 3433);
FORCEPROP 2 LAST CDS_LIB mstr_standard
J 0
(-5950 3425);
DISPLAY 0.723404 (-5950 3425);
PAINT MONO (-5950 3425);
DISPLAY INVISIBLE (-5950 3425);
FORCEPROP 1 LAST BODY_TYPE PLUMBING
J 2
(-5950 3475);
DISPLAY 0.872340 (-5950 3475);
PAINT GREEN (-5950 3475);
DISPLAY INVISIBLE (-5950 3475);
FORCEPROP 1 LAST HDL_TAP TRUE
J 2
(-6275 3300);
DISPLAY 0.872340 (-6275 3300);
DISPLAY INVISIBLE (-6275 3300);
FORCEPROP 1 LAST PATH I295
J 2
(-5948 3425);
DISPLAY 0.872340 (-5948 3425);
PAINT GREEN (-5948 3425);
DISPLAY INVISIBLE (-5948 3425);
FORCEADD TAP..1
R 2
(-5950 3475);
FORCEPROP 3 LASTPIN (-5900 3475) SIG_NAME M_D_CPU1_SB_CA<0>
J 0
(-5890 3485);
DISPLAY 0.659574 (-5890 3485);
PAINT MONO (-5890 3485);
DISPLAY INVISIBLE (-5890 3485);
FORCEPROP 1 LASTPIN (-5900 3475) BN 0
J 2
(-5888 3483);
DISPLAY 0.489362 (-5888 3483);
PAINT GREEN (-5888 3483);
FORCEPROP 2 LAST CDS_LIB mstr_standard
J 0
(-5950 3475);
DISPLAY 0.723404 (-5950 3475);
PAINT MONO (-5950 3475);
DISPLAY INVISIBLE (-5950 3475);
FORCEPROP 1 LAST BODY_TYPE PLUMBING
J 2
(-5950 3525);
DISPLAY 0.872340 (-5950 3525);
PAINT GREEN (-5950 3525);
DISPLAY INVISIBLE (-5950 3525);
FORCEPROP 1 LAST HDL_TAP TRUE
J 2
(-6275 3350);
DISPLAY 0.872340 (-6275 3350);
DISPLAY INVISIBLE (-6275 3350);
FORCEPROP 1 LAST PATH I296
J 2
(-5948 3475);
DISPLAY 0.872340 (-5948 3475);
PAINT GREEN (-5948 3475);
DISPLAY INVISIBLE (-5948 3475);
FORCEADD TAP..1
R 2
(-5950 3325);
FORCEPROP 3 LASTPIN (-5900 3325) SIG_NAME M_D_CPU1_SB_CA<3>
J 0
(-5890 3335);
DISPLAY 0.659574 (-5890 3335);
PAINT MONO (-5890 3335);
DISPLAY INVISIBLE (-5890 3335);
FORCEPROP 1 LASTPIN (-5900 3325) BN 3
J 2
(-5888 3333);
DISPLAY 0.489362 (-5888 3333);
PAINT GREEN (-5888 3333);
FORCEPROP 2 LAST CDS_LIB mstr_standard
J 0
(-5950 3325);
DISPLAY 0.723404 (-5950 3325);
PAINT MONO (-5950 3325);
DISPLAY INVISIBLE (-5950 3325);
FORCEPROP 1 LAST BODY_TYPE PLUMBING
J 2
(-5950 3375);
DISPLAY 0.872340 (-5950 3375);
PAINT GREEN (-5950 3375);
DISPLAY INVISIBLE (-5950 3375);
FORCEPROP 1 LAST HDL_TAP TRUE
J 2
(-6275 3200);
DISPLAY 0.872340 (-6275 3200);
DISPLAY INVISIBLE (-6275 3200);
FORCEPROP 1 LAST PATH I297
J 2
(-5948 3325);
DISPLAY 0.872340 (-5948 3325);
PAINT GREEN (-5948 3325);
DISPLAY INVISIBLE (-5948 3325);
FORCEADD TAP..1
R 2
(-5950 3375);
FORCEPROP 3 LASTPIN (-5900 3375) SIG_NAME M_D_CPU1_SB_CA<2>
J 0
(-5890 3385);
DISPLAY 0.659574 (-5890 3385);
PAINT MONO (-5890 3385);
DISPLAY INVISIBLE (-5890 3385);
FORCEPROP 1 LASTPIN (-5900 3375) BN 2
J 2
(-5888 3383);
DISPLAY 0.489362 (-5888 3383);
PAINT GREEN (-5888 3383);
FORCEPROP 2 LAST CDS_LIB mstr_standard
J 0
(-5950 3375);
DISPLAY 0.723404 (-5950 3375);
PAINT MONO (-5950 3375);
DISPLAY INVISIBLE (-5950 3375);
FORCEPROP 1 LAST BODY_TYPE PLUMBING
J 2
(-5950 3425);
DISPLAY 0.872340 (-5950 3425);
PAINT GREEN (-5950 3425);
DISPLAY INVISIBLE (-5950 3425);
FORCEPROP 1 LAST HDL_TAP TRUE
J 2
(-6275 3250);
DISPLAY 0.872340 (-6275 3250);
DISPLAY INVISIBLE (-6275 3250);
FORCEPROP 1 LAST PATH I298
J 2
(-5948 3375);
DISPLAY 0.872340 (-5948 3375);
PAINT GREEN (-5948 3375);
DISPLAY INVISIBLE (-5948 3375);
FORCEADD TAP..1
R 2
(-5950 3275);
FORCEPROP 3 LASTPIN (-5900 3275) SIG_NAME M_D_CPU1_SB_CA<4>
J 0
(-5890 3285);
DISPLAY 0.659574 (-5890 3285);
PAINT MONO (-5890 3285);
DISPLAY INVISIBLE (-5890 3285);
FORCEPROP 1 LASTPIN (-5900 3275) BN 4
J 2
(-5888 3283);
DISPLAY 0.489362 (-5888 3283);
PAINT GREEN (-5888 3283);
FORCEPROP 2 LAST CDS_LIB mstr_standard
J 0
(-5950 3275);
DISPLAY 0.723404 (-5950 3275);
PAINT MONO (-5950 3275);
DISPLAY INVISIBLE (-5950 3275);
FORCEPROP 1 LAST BODY_TYPE PLUMBING
J 2
(-5950 3325);
DISPLAY 0.872340 (-5950 3325);
PAINT GREEN (-5950 3325);
DISPLAY INVISIBLE (-5950 3325);
FORCEPROP 1 LAST HDL_TAP TRUE
J 2
(-6275 3150);
DISPLAY 0.872340 (-6275 3150);
DISPLAY INVISIBLE (-6275 3150);
FORCEPROP 1 LAST PATH I299
J 2
(-5948 3275);
DISPLAY 0.872340 (-5948 3275);
PAINT GREEN (-5948 3275);
DISPLAY INVISIBLE (-5948 3275);
FORCEADD TAP..1
R 2
(-5950 3225);
FORCEPROP 3 LASTPIN (-5900 3225) SIG_NAME M_D_CPU1_SB_CA<5>
J 0
(-5890 3235);
DISPLAY 0.659574 (-5890 3235);
PAINT MONO (-5890 3235);
DISPLAY INVISIBLE (-5890 3235);
FORCEPROP 1 LASTPIN (-5900 3225) BN 5
J 2
(-5888 3233);
DISPLAY 0.489362 (-5888 3233);
PAINT GREEN (-5888 3233);
FORCEPROP 2 LAST CDS_LIB mstr_standard
J 0
(-5950 3225);
DISPLAY 0.723404 (-5950 3225);
PAINT MONO (-5950 3225);
DISPLAY INVISIBLE (-5950 3225);
FORCEPROP 1 LAST BODY_TYPE PLUMBING
J 2
(-5950 3275);
DISPLAY 0.872340 (-5950 3275);
PAINT GREEN (-5950 3275);
DISPLAY INVISIBLE (-5950 3275);
FORCEPROP 1 LAST HDL_TAP TRUE
J 2
(-6275 3100);
DISPLAY 0.872340 (-6275 3100);
DISPLAY INVISIBLE (-6275 3100);
FORCEPROP 1 LAST PATH I300
J 2
(-5948 3225);
DISPLAY 0.872340 (-5948 3225);
PAINT GREEN (-5948 3225);
DISPLAY INVISIBLE (-5948 3225);
FORCEADD TAP..1
R 2
(-5950 3175);
FORCEPROP 3 LASTPIN (-5900 3175) SIG_NAME M_D_CPU1_SB_CA<6>
J 0
(-5890 3185);
DISPLAY 0.659574 (-5890 3185);
PAINT MONO (-5890 3185);
DISPLAY INVISIBLE (-5890 3185);
FORCEPROP 1 LASTPIN (-5900 3175) BN 6
J 2
(-5888 3183);
DISPLAY 0.489362 (-5888 3183);
PAINT GREEN (-5888 3183);
FORCEPROP 2 LAST CDS_LIB mstr_standard
J 0
(-5950 3175);
DISPLAY 0.723404 (-5950 3175);
PAINT MONO (-5950 3175);
DISPLAY INVISIBLE (-5950 3175);
FORCEPROP 1 LAST BODY_TYPE PLUMBING
J 2
(-5950 3225);
DISPLAY 0.872340 (-5950 3225);
PAINT GREEN (-5950 3225);
DISPLAY INVISIBLE (-5950 3225);
FORCEPROP 1 LAST HDL_TAP TRUE
J 2
(-6275 3050);
DISPLAY 0.872340 (-6275 3050);
DISPLAY INVISIBLE (-6275 3050);
FORCEPROP 1 LAST PATH I301
J 2
(-5948 3175);
DISPLAY 0.872340 (-5948 3175);
PAINT GREEN (-5948 3175);
DISPLAY INVISIBLE (-5948 3175);
FORCEADD OFFPAGE..2
R 2
(-6550 3900);
FORCEPROP 2 LAST $XR0 101 
J 0
(-6805 3900);
DISPLAY 0.638298 (-6805 3900);
PAINT MONO (-6805 3900);
FORCEPROP 2 LAST CDS_LIB standard
J 0
(-6550 3900);
DISPLAY INVISIBLE (-6550 3900);
FORCEPROP 1 LAST OFFPAGE TRUE
J 2
(-6875 3775);
DISPLAY 0.872340 (-6875 3775);
PAINT GREEN (-6875 3775);
DISPLAY INVISIBLE (-6875 3775);
FORCEPROP 1 LAST COMMENT_BODY TRUE
J 2
(-6505 3805);
DISPLAY 0.872340 (-6505 3805);
PAINT GREEN (-6505 3805);
DISPLAY INVISIBLE (-6505 3805);
FORCEPROP 2 LAST PATH I302
J 0
(-6800 3950);
DISPLAY 1.021277 (-6800 3950);
DISPLAY INVISIBLE (-6800 3950);
FORCEADD OFFPAGE..2
R 2
(-6550 3500);
FORCEPROP 2 LAST $XR0 101 
J 0
(-6805 3500);
DISPLAY 0.638298 (-6805 3500);
PAINT MONO (-6805 3500);
FORCEPROP 2 LAST CDS_LIB standard
J 0
(-6550 3500);
DISPLAY INVISIBLE (-6550 3500);
FORCEPROP 1 LAST OFFPAGE TRUE
J 2
(-6875 3375);
DISPLAY 0.872340 (-6875 3375);
PAINT GREEN (-6875 3375);
DISPLAY INVISIBLE (-6875 3375);
FORCEPROP 1 LAST COMMENT_BODY TRUE
J 2
(-6505 3405);
DISPLAY 0.872340 (-6505 3405);
PAINT GREEN (-6505 3405);
DISPLAY INVISIBLE (-6505 3405);
FORCEPROP 2 LAST PATH I303
J 0
(-6800 3550);
DISPLAY 1.021277 (-6800 3550);
DISPLAY INVISIBLE (-6800 3550);
FORCEADD OFFPAGE..2
R 2
(-6550 3025);
FORCEPROP 2 LAST $XR0 101 
J 0
(-6805 3025);
DISPLAY 0.638298 (-6805 3025);
PAINT MONO (-6805 3025);
FORCEPROP 2 LAST CDS_LIB standard
J 0
(-6550 3025);
DISPLAY INVISIBLE (-6550 3025);
FORCEPROP 1 LAST OFFPAGE TRUE
J 2
(-6875 2900);
DISPLAY 0.872340 (-6875 2900);
PAINT GREEN (-6875 2900);
DISPLAY INVISIBLE (-6875 2900);
FORCEPROP 1 LAST COMMENT_BODY TRUE
J 2
(-6505 2930);
DISPLAY 0.872340 (-6505 2930);
PAINT GREEN (-6505 2930);
DISPLAY INVISIBLE (-6505 2930);
FORCEPROP 2 LAST PATH I304
J 0
(-6800 3075);
DISPLAY 1.021277 (-6800 3075);
DISPLAY INVISIBLE (-6800 3075);
FORCEADD OFFPAGE..2
R 2
(-6550 2975);
FORCEPROP 2 LAST $XR0 101 
J 0
(-6805 2975);
DISPLAY 0.638298 (-6805 2975);
PAINT MONO (-6805 2975);
FORCEPROP 2 LAST CDS_LIB standard
J 0
(-6550 2975);
DISPLAY INVISIBLE (-6550 2975);
FORCEPROP 1 LAST OFFPAGE TRUE
J 2
(-6875 2850);
DISPLAY 0.872340 (-6875 2850);
PAINT GREEN (-6875 2850);
DISPLAY INVISIBLE (-6875 2850);
FORCEPROP 1 LAST COMMENT_BODY TRUE
J 2
(-6505 2880);
DISPLAY 0.872340 (-6505 2880);
PAINT GREEN (-6505 2880);
DISPLAY INVISIBLE (-6505 2880);
FORCEPROP 2 LAST PATH I305
J 0
(-6800 3025);
DISPLAY 1.021277 (-6800 3025);
DISPLAY INVISIBLE (-6800 3025);
FORCEADD OFFPAGE..2
R 2
(-6550 2875);
FORCEPROP 2 LAST $XR0 101 
J 0
(-6805 2875);
DISPLAY 0.638298 (-6805 2875);
PAINT MONO (-6805 2875);
FORCEPROP 2 LAST CDS_LIB standard
J 0
(-6550 2875);
DISPLAY INVISIBLE (-6550 2875);
FORCEPROP 1 LAST OFFPAGE TRUE
J 2
(-6875 2750);
DISPLAY 0.872340 (-6875 2750);
PAINT GREEN (-6875 2750);
DISPLAY INVISIBLE (-6875 2750);
FORCEPROP 1 LAST COMMENT_BODY TRUE
J 2
(-6505 2780);
DISPLAY 0.872340 (-6505 2780);
PAINT GREEN (-6505 2780);
DISPLAY INVISIBLE (-6505 2780);
FORCEPROP 2 LAST PATH I306
J 0
(-6800 2925);
DISPLAY 1.021277 (-6800 2925);
DISPLAY INVISIBLE (-6800 2925);
FORCEADD OFFPAGE..2
R 2
(-6550 2825);
FORCEPROP 2 LAST $XR0 101 
J 0
(-6805 2825);
DISPLAY 0.638298 (-6805 2825);
PAINT MONO (-6805 2825);
FORCEPROP 2 LAST CDS_LIB standard
J 0
(-6550 2825);
DISPLAY INVISIBLE (-6550 2825);
FORCEPROP 1 LAST OFFPAGE TRUE
J 2
(-6875 2700);
DISPLAY 0.872340 (-6875 2700);
PAINT GREEN (-6875 2700);
DISPLAY INVISIBLE (-6875 2700);
FORCEPROP 1 LAST COMMENT_BODY TRUE
J 2
(-6505 2730);
DISPLAY 0.872340 (-6505 2730);
PAINT GREEN (-6505 2730);
DISPLAY INVISIBLE (-6505 2730);
FORCEPROP 2 LAST PATH I307
J 0
(-6800 2875);
DISPLAY 1.021277 (-6800 2875);
DISPLAY INVISIBLE (-6800 2875);
FORCEADD OFFPAGE..1
(-6550 2725);
FORCEPROP 2 LAST $XR0 101 
J 0
(-6832 2725);
DISPLAY 0.638298 (-6832 2725);
PAINT MONO (-6832 2725);
FORCEPROP 2 LAST CDS_LIB standard
J 0
(-6550 2725);
DISPLAY INVISIBLE (-6550 2725);
FORCEPROP 1 LAST OFFPAGE TRUE
J 0
(-6225 2600);
DISPLAY 0.872340 (-6225 2600);
PAINT GREEN (-6225 2600);
DISPLAY INVISIBLE (-6225 2600);
FORCEPROP 1 LAST COMMENT_BODY TRUE
J 0
(-6425 2625);
DISPLAY 0.872340 (-6425 2625);
PAINT GREEN (-6425 2625);
DISPLAY INVISIBLE (-6425 2625);
FORCEPROP 2 LAST PATH I308
J 0
(-6825 2775);
DISPLAY 1.021277 (-6825 2775);
DISPLAY INVISIBLE (-6825 2775);
FORCEADD OFFPAGE..5
(-6550 2625);
FORCEPROP 2 LAST $XR0 101 
J 0
(-6805 2625);
DISPLAY 0.638298 (-6805 2625);
PAINT MONO (-6805 2625);
FORCEPROP 2 LAST CDS_LIB mstr_standard
J 0
(-6550 2625);
DISPLAY INVISIBLE (-6550 2625);
FORCEPROP 1 LAST OFFPAGE TRUE
J 0
(-6225 2500);
DISPLAY 0.872340 (-6225 2500);
PAINT GREEN (-6225 2500);
DISPLAY INVISIBLE (-6225 2500);
FORCEPROP 1 LAST COMMENT_BODY TRUE
J 0
(-6450 2550);
DISPLAY 0.872340 (-6450 2550);
PAINT GREEN (-6450 2550);
DISPLAY INVISIBLE (-6450 2550);
FORCEPROP 2 LAST PATH I309
J 0
(-6800 2675);
DISPLAY 1.021277 (-6800 2675);
DISPLAY INVISIBLE (-6800 2675);
FORCEADD OFFPAGE..2
R 2
(-6550 2525);
FORCEPROP 2 LAST $XR0 101 
J 0
(-6805 2525);
DISPLAY 0.638298 (-6805 2525);
PAINT MONO (-6805 2525);
FORCEPROP 2 LAST CDS_LIB standard
J 0
(-6550 2525);
DISPLAY INVISIBLE (-6550 2525);
FORCEPROP 1 LAST OFFPAGE TRUE
J 2
(-6875 2400);
DISPLAY 0.872340 (-6875 2400);
PAINT GREEN (-6875 2400);
DISPLAY INVISIBLE (-6875 2400);
FORCEPROP 1 LAST COMMENT_BODY TRUE
J 2
(-6505 2430);
DISPLAY 0.872340 (-6505 2430);
PAINT GREEN (-6505 2430);
DISPLAY INVISIBLE (-6505 2430);
FORCEPROP 2 LAST PATH I310
J 0
(-6800 2575);
DISPLAY 1.021277 (-6800 2575);
DISPLAY INVISIBLE (-6800 2575);
FORCEADD OFFPAGE..2
R 2
(-6550 2475);
FORCEPROP 2 LAST $XR0 101 
J 0
(-6805 2475);
DISPLAY 0.638298 (-6805 2475);
PAINT MONO (-6805 2475);
FORCEPROP 2 LAST CDS_LIB standard
J 0
(-6550 2475);
DISPLAY INVISIBLE (-6550 2475);
FORCEPROP 1 LAST OFFPAGE TRUE
J 2
(-6875 2350);
DISPLAY 0.872340 (-6875 2350);
PAINT GREEN (-6875 2350);
DISPLAY INVISIBLE (-6875 2350);
FORCEPROP 1 LAST COMMENT_BODY TRUE
J 2
(-6505 2380);
DISPLAY 0.872340 (-6505 2380);
PAINT GREEN (-6505 2380);
DISPLAY INVISIBLE (-6505 2380);
FORCEPROP 2 LAST PATH I311
J 0
(-6800 2525);
DISPLAY 1.021277 (-6800 2525);
DISPLAY INVISIBLE (-6800 2525);
FORCEADD OFFPAGE..1
(-6550 2375);
FORCEPROP 2 LAST $XR0 101 
J 0
(-6832 2375);
DISPLAY 0.638298 (-6832 2375);
PAINT MONO (-6832 2375);
FORCEPROP 2 LAST CDS_LIB standard
J 0
(-6550 2375);
DISPLAY INVISIBLE (-6550 2375);
FORCEPROP 1 LAST OFFPAGE TRUE
J 0
(-6225 2250);
DISPLAY 0.872340 (-6225 2250);
PAINT GREEN (-6225 2250);
DISPLAY INVISIBLE (-6225 2250);
FORCEPROP 1 LAST COMMENT_BODY TRUE
J 0
(-6425 2275);
DISPLAY 0.872340 (-6425 2275);
PAINT GREEN (-6425 2275);
DISPLAY INVISIBLE (-6425 2275);
FORCEPROP 2 LAST PATH I312
J 0
(-6825 2425);
DISPLAY 1.021277 (-6825 2425);
DISPLAY INVISIBLE (-6825 2425);
FORCEADD OFFPAGE..5
(-6550 2275);
FORCEPROP 2 LAST $XR0 101 
J 0
(-6805 2275);
DISPLAY 0.638298 (-6805 2275);
PAINT MONO (-6805 2275);
FORCEPROP 2 LAST CDS_LIB standard
J 0
(-6550 2275);
DISPLAY INVISIBLE (-6550 2275);
FORCEPROP 1 LAST OFFPAGE TRUE
J 0
(-6225 2150);
DISPLAY 0.872340 (-6225 2150);
PAINT GREEN (-6225 2150);
DISPLAY INVISIBLE (-6225 2150);
FORCEPROP 1 LAST COMMENT_BODY TRUE
J 0
(-6450 2200);
DISPLAY 0.872340 (-6450 2200);
PAINT GREEN (-6450 2200);
DISPLAY INVISIBLE (-6450 2200);
FORCEPROP 2 LAST PATH I313
J 0
(-6800 2325);
DISPLAY 1.021277 (-6800 2325);
DISPLAY INVISIBLE (-6800 2325);
FORCEADD Q_RES..1
(-6625 2175);
FORCEPROP 1 LAST LOCATION R503
J 0
(-6950 2175);
DISPLAY 0.489362 (-6950 2175);
PAINT SKYBLUE (-6950 2175);
FORCEPROP 0 LAST $SEC 1
J 0
(-6800 2225);
DISPLAY 0.680851 (-6800 2225);
PAINT MONO (-6800 2225);
DISPLAY INVISIBLE (-6800 2225);
FORCEPROP 0 LAST CDS_SEC 1
J 0
(-6800 2225);
DISPLAY 1.021277 (-6800 2225);
DISPLAY INVISIBLE (-6800 2225);
FORCEPROP 1 LASTPIN (-6725 2175) $PN 1
J 0
(-6713 2187);
DISPLAY 0.489362 (-6713 2187);
PAINT MONO (-6713 2187);
FORCEPROP 1 LASTPIN (-6525 2175) $PN 2
J 0
(-6563 2187);
DISPLAY 0.489362 (-6563 2187);
PAINT MONO (-6563 2187);
FORCEPROP 1 LAST PACK_TYPE 0402LF
J 0
(-6950 2150);
DISPLAY 0.489362 (-6950 2150);
PAINT SKYBLUE (-6950 2150);
FORCEPROP 1 LAST TOLERANCE 1%
J 0
(-6350 2175);
DISPLAY 0.489362 (-6350 2175);
PAINT SKYBLUE (-6350 2175);
FORCEPROP 1 LAST VALUE 15
J 2
(-6300 2175);
DISPLAY 0.489362 (-6300 2175);
PAINT SKYBLUE (-6300 2175);
FORCEPROP 1 LAST MATERIAL CHIP
J 0
(-6750 2300);
DISPLAY 0.638298 (-6750 2300);
PAINT SKYBLUE (-6750 2300);
DISPLAY INVISIBLE (-6750 2300);
FORCEPROP 1 LAST WATTAGE 1/16W
J 2
(-6400 2300);
DISPLAY 0.638298 (-6400 2300);
PAINT SKYBLUE (-6400 2300);
DISPLAY INVISIBLE (-6400 2300);
FORCEPROP 2 LAST CDS_LIB pure_quanta
J 0
(-6625 2175);
DISPLAY INVISIBLE (-6625 2175);
FORCEPROP 1 LAST PATH I314
J 0
(-6675 2325);
DISPLAY 0.978723 (-6675 2325);
PAINT WHITE (-6675 2325);
DISPLAY INVISIBLE (-6675 2325);
FORCEPROP 1 LAST PART_NUMBER CS01502FB03
J 0
(-6500 2150);
DISPLAY 0.489362 (-6500 2150);
PAINT SKYBLUE (-6500 2150);
DISPLAY INVISIBLE (-6500 2150);
FORCEADD OFFPAGE..1
(-7500 2175);
FORCEPROP 2 LAST $XR0 101 
J 0
(-7752 2175);
DISPLAY 0.638298 (-7752 2175);
PAINT MONO (-7752 2175);
FORCEPROP 2 LAST CDS_LIB mstr_standard
J 0
(-7500 2175);
DISPLAY INVISIBLE (-7500 2175);
FORCEPROP 1 LAST OFFPAGE TRUE
J 0
(-7175 2050);
DISPLAY 0.872340 (-7175 2050);
PAINT GREEN (-7175 2050);
DISPLAY INVISIBLE (-7175 2050);
FORCEPROP 1 LAST COMMENT_BODY TRUE
J 0
(-7375 2075);
DISPLAY 0.872340 (-7375 2075);
PAINT GREEN (-7375 2075);
DISPLAY INVISIBLE (-7375 2075);
FORCEPROP 2 LAST PATH I315
J 0
(-7750 2225);
DISPLAY 1.021277 (-7750 2225);
DISPLAY INVISIBLE (-7750 2225);
FORCEADD OFFPAGE..5
(-6550 2075);
FORCEPROP 2 LAST $XR0 101 
J 0
(-6805 2075);
DISPLAY 0.638298 (-6805 2075);
PAINT MONO (-6805 2075);
FORCEPROP 2 LAST CDS_LIB standard
J 0
(-6550 2075);
DISPLAY INVISIBLE (-6550 2075);
FORCEPROP 1 LAST OFFPAGE TRUE
J 0
(-6225 1950);
DISPLAY 0.872340 (-6225 1950);
PAINT GREEN (-6225 1950);
DISPLAY INVISIBLE (-6225 1950);
FORCEPROP 1 LAST COMMENT_BODY TRUE
J 0
(-6450 2000);
DISPLAY 0.872340 (-6450 2000);
PAINT GREEN (-6450 2000);
DISPLAY INVISIBLE (-6450 2000);
FORCEPROP 2 LAST PATH I316
J 0
(-6800 2125);
DISPLAY 1.021277 (-6800 2125);
DISPLAY INVISIBLE (-6800 2125);
FORCEADD CAD_NOTE..1
(-7725 2475);
FORCEPROP 0 LAST L1 R1961 PLACE CLOSE TO CPU < 25MM
J 0
(-7875 2350);
DISPLAY 0.617021 (-7875 2350);
PAINT WHITE (-7875 2350);
FORCEPROP 2 LAST CDS_LIB pure_quanta_power
J 0
(-7725 2475);
DISPLAY INVISIBLE (-7725 2475);
FORCEPROP 1 LAST COMMENT_BODY TRUE
J 0
(-7700 2575);
DISPLAY 0.574468 (-7700 2575);
PAINT WHITE (-7700 2575);
DISPLAY INVISIBLE (-7700 2575);
FORCEADD QUANTA_TITLE_BLOCK_C..1
(-100 100);
FORCEPROP 0 LAST CDS_CON_LAST_MODIFIED Thu Sep 14 16:11:56 2023
J 0
(-1985 115);
DISPLAY INVISIBLE (-1985 115);
FORCEPROP 1 LAST CUSTOM_TXT_CDS <CON_LAST_MODIFIED>
J 0
(-1985 115);
DISPLAY 0.978723 (-1985 115);
FORCEPROP 2 LAST CUSTOM_TXT_CDS <XR_PAGE_TITLE>
J 0
(-7990 5350);
DISPLAY 0.638298 (-7990 5350);
PAINT PINK (-7990 5350);
DISPLAY INVISIBLE (-7990 5350);
FORCEPROP 1 LAST CUSTOM_TXT_CDS <NAME_2>
J 0
(-3275 150);
FORCEPROP 1 LAST CUSTOM_TXT_CDS <NAME_1>
J 0
(-3275 275);
FORCEPROP 1 LAST CUSTOM_TXT_CDS <Q_NUMBER>
J 0
(-1503 203);
DISPLAY 1.212766 (-1503 203);
FORCEPROP 1 LAST CUSTOM_TXT_CDS <Q_PROJ>
J 0
(-2482 202);
DISPLAY 1.212766 (-2482 202);
FORCEPROP 1 LAST CUSTOM_TXT_CDS <Q_REV>
J 0
(-284 203);
DISPLAY 1.212766 (-284 203);
FORCEPROP 1 LAST CUSTOM_TXT_CDS <CON_PAGE_NUM> OF <CON_TOTAL_PAGES>
J 0
(-546 118);
DISPLAY 0.978723 (-546 118);
FORCEPROP 1 LAST Q_TITLE CPU1 DDR CHD
J 0
(-9400 150);
DISPLAY 2.446809 (-9400 150);
PAINT GREEN (-9400 150);
FORCEPROP 2 LAST PAGE_BORDER TRUE
J 0
(-7990 5350);
DISPLAY 0.638298 (-7990 5350);
PAINT PINK (-7990 5350);
DISPLAY INVISIBLE (-7990 5350);
FORCEPROP 2 LAST CDS_LIB pure_quanta
J 0
(-100 100);
DISPLAY INVISIBLE (-100 100);
FORCEPROP 1 LAST CDS_LMAN_SYM_OUTLINE -9475,6775,100,-125
J 0
(-100 100);
DISPLAY 0.468085 (-100 100);
PAINT GREEN (-100 100);
DISPLAY INVISIBLE (-100 100);
FORCEPROP 2 LAST CDS_XR_PAGE_TITLE CR-40 : @T6G_MB_LIB.T6G(SCH_1):PAGE40
J 0
(-7990 5350);
DISPLAY 0.638298 (-7990 5350);
PAINT PINK (-7990 5350);
DISPLAY INVISIBLE (-7990 5350);
FORCEPROP 1 LAST Q_DEPT BU9
J 1
(-3863 149);
DISPLAY 1.957447 (-3863 149);
PAINT GREEN (-3863 149);
DISPLAY INVISIBLE (-3863 149);
FORCEPROP 1 LAST COMMENT_BODY TRUE
J 0
(-88 87);
DISPLAY 0.978723 (-88 87);
PAINT GREEN (-88 87);
DISPLAY INVISIBLE (-88 87);
WIRE 17 -1 (-3275 5950)(-3275 5900);
WIRE 17 -1 (-3275 6000)(-3275 5950);
WIRE 17 -1 (-3275 5900)(-3275 5850);
WIRE 17 -1 (-3275 5850)(-3275 5800);
WIRE 17 -1 (-3275 6050)(-3275 6000);
WIRE 17 -1 (-3275 6050)(-2650 6050);
FORCEPROP 2 LAST SIG_NAME M_D_CPU1_SA_DQ<31:0>
J 2
(-2710 6060);
DISPLAY 0.489362 (-2710 6060);
WIRE 17 -1 (-3275 5800)(-3275 5750);
WIRE 17 -1 (-3275 5750)(-3275 5700);
WIRE 17 -1 (-3275 5700)(-3275 5600);
WIRE 17 -1 (-3275 5600)(-3275 5550);
WIRE 17 -1 (-3275 5550)(-3275 5500);
WIRE 17 -1 (-3275 5500)(-3275 5450);
WIRE 17 -1 (-3275 5450)(-3275 5400);
WIRE 17 -1 (-3275 5400)(-3275 5350);
WIRE 17 -1 (-3275 5350)(-3275 5300);
WIRE 17 -1 (-3275 5300)(-3275 5250);
WIRE 17 -1 (-3275 5150)(-3275 5250);
WIRE 17 -1 (-3275 5100)(-3275 5150);
WIRE 17 -1 (-3275 5050)(-3275 5100);
WIRE 17 -1 (-3275 5000)(-3275 5050);
WIRE 17 -1 (-3275 5000)(-3275 4950);
WIRE 17 -1 (-3275 4950)(-3275 4900);
WIRE 17 -1 (-3275 4900)(-3275 4850);
WIRE 17 -1 (-3275 4850)(-3275 4800);
WIRE 17 -1 (-3275 4800)(-3275 4700);
WIRE 17 -1 (-3275 4700)(-3275 4650);
WIRE 17 -1 (-3275 4650)(-3275 4600);
WIRE 17 -1 (-3275 4600)(-3275 4550);
WIRE 17 -1 (-3275 4500)(-3275 4550);
WIRE 17 -1 (-3275 4450)(-3275 4500);
WIRE 17 -1 (-3275 4400)(-3275 4450);
WIRE 17 -1 (-3275 4350)(-3275 4400);
WIRE 17 -1 (-3275 4200)(-3275 4150);
WIRE 17 -1 (-3275 4250)(-3275 4200);
WIRE 17 -1 (-3275 4150)(-3275 4100);
WIRE 17 -1 (-3275 4100)(-3275 4050);
WIRE 17 -1 (-3275 4250)(-2650 4250);
FORCEPROP 2 LAST SIG_NAME M_D_CPU1_SB_DQ<31:0>
J 2
(-2710 4260);
DISPLAY 0.489362 (-2710 4260);
WIRE 17 -1 (-3275 3650)(-3275 3600);
WIRE 17 -1 (-3275 3700)(-3275 3650);
WIRE 17 -1 (-3275 3600)(-3275 3550);
WIRE 17 -1 (-3275 3550)(-3275 3500);
WIRE 17 -1 (-3275 3750)(-3275 3700);
WIRE 17 -1 (-3275 3800)(-3275 3750);
WIRE 17 -1 (-3275 3500)(-3275 3450);
WIRE 17 -1 (-3275 3350)(-3275 3450);
WIRE 17 -1 (-3275 3900)(-3275 3800);
WIRE 17 -1 (-3275 3950)(-3275 3900);
WIRE 17 -1 (-3275 3300)(-3275 3350);
WIRE 17 -1 (-3275 3250)(-3275 3300);
WIRE 17 -1 (-3275 4000)(-3275 3950);
WIRE 17 -1 (-3275 4050)(-3275 4000);
WIRE 17 -1 (-3275 3200)(-3275 3250);
WIRE 17 -1 (-3275 3200)(-3275 3150);
WIRE 17 -1 (-3275 3150)(-3275 3100);
WIRE 17 -1 (-3275 3100)(-3275 3050);
WIRE 17 -1 (-3275 3050)(-3275 3000);
WIRE 17 -1 (-3275 3000)(-3275 2900);
WIRE 17 -1 (-3275 2900)(-3275 2850);
WIRE 17 -1 (-3275 2850)(-3275 2800);
WIRE 17 -1 (-3275 2800)(-3275 2750);
WIRE 17 -1 (-3275 2700)(-3275 2750);
WIRE 17 -1 (-3275 2650)(-3275 2700);
WIRE 17 -1 (-3275 2600)(-3275 2650);
WIRE 17 -1 (-3275 2550)(-3275 2600);
WIRE 17 -1 (-3275 2450)(-3275 2475);
WIRE 17 -1 (-3275 2450)(-3275 2400);
WIRE 17 -1 (-3275 2475)(-2775 2475);
FORCEPROP 2 LAST SIG_NAME M_D_CPU1_SA_CB<7:0>
J 2
(-2775 2485);
DISPLAY 0.489362 (-2775 2485);
WIRE 17 -1 (-3275 2350)(-3275 2400);
WIRE 17 -1 (-3275 2350)(-3275 2300);
WIRE 17 -1 (-3275 2250)(-3275 2300);
WIRE 17 -1 (-3275 2200)(-3275 2250);
WIRE 17 -1 (-3275 2150)(-3275 2200);
WIRE 17 -1 (-3275 2100)(-3275 2150);
WIRE 17 -1 (-3275 1900)(-3275 1850);
WIRE 17 -1 (-3275 1900)(-3275 1950);
WIRE 17 -1 (-3275 1800)(-3275 1850);
WIRE 17 -1 (-3275 1750)(-3275 1800);
WIRE 17 -1 (-3275 2000)(-3275 1950);
WIRE 17 -1 (-3275 2000)(-3275 2025);
WIRE 17 -1 (-3275 1700)(-3275 1750);
WIRE 17 -1 (-3275 1650)(-3275 1700);
WIRE 17 -1 (-3275 2025)(-2775 2025);
FORCEPROP 2 LAST SIG_NAME M_D_CPU1_SB_CB<7:0>
J 2
(-2775 2035);
DISPLAY 0.489362 (-2775 2035);
WIRE 17 -1 (-6000 5500)(-6000 5600);
WIRE 17 -1 (-6000 5400)(-6000 5500);
WIRE 17 -1 (-6000 5700)(-6000 5600);
WIRE 17 -1 (-6000 5800)(-6000 5700);
WIRE 17 -1 (-6000 5300)(-6000 5400);
WIRE 17 -1 (-6000 5300)(-6000 5200);
WIRE 17 -1 (-6000 5900)(-6000 5800);
WIRE 17 -1 (-6000 6000)(-6000 5900);
FORCEPROP 2 LAST SIG_NAME M_D_CPU1_SA_DQS_DN<9:0>
J 2
(-6035 6010);
DISPLAY 0.489362 (-6035 6010);
WIRE 17 -1 (-5800 6050)(-5800 5950);
WIRE 17 -1 (-5800 6050)(-6600 6050);
FORCEPROP 2 LAST SIG_NAME M_D_CPU1_SA_DQS_DP<9:0>
J 2
(-6035 6060);
DISPLAY 0.489362 (-6035 6060);
WIRE 17 -1 (-6000 5200)(-6000 5100);
WIRE 17 -1 (-5800 5950)(-5800 5850);
WIRE 17 -1 (-5800 5850)(-5800 5750);
WIRE 17 -1 (-5800 5750)(-5800 5650);
WIRE 17 -1 (-5800 5550)(-5800 5650);
WIRE 17 -1 (-5800 5450)(-5800 5550);
WIRE 17 -1 (-5800 5350)(-5800 5450);
WIRE 17 -1 (-5800 5350)(-5800 5250);
WIRE 17 -1 (-5800 5250)(-5800 5150);
WIRE 17 -1 (-6000 4950)(-6000 4850);
FORCEPROP 2 LAST SIG_NAME M_D_CPU1_SB_DQS_DN<9:0>
J 2
(-6035 4960);
DISPLAY 0.489362 (-6035 4960);
WIRE 17 -1 (-6000 4850)(-6000 4750);
WIRE 17 -1 (-6000 4750)(-6000 4650);
WIRE 17 -1 (-6000 4650)(-6000 4550);
WIRE 17 -1 (-6000 4450)(-6000 4550);
WIRE 17 -1 (-6000 4350)(-6000 4450);
WIRE 17 -1 (-5800 5000)(-5800 4900);
WIRE 17 -1 (-5800 5000)(-6600 5000);
FORCEPROP 2 LAST SIG_NAME M_D_CPU1_SB_DQS_DP<9:0>
J 2
(-6035 5010);
DISPLAY 0.489362 (-6035 5010);
WIRE 17 -1 (-6000 4250)(-6000 4350);
WIRE 17 -1 (-6000 4250)(-6000 4150);
WIRE 17 -1 (-6000 4150)(-6000 4050);
WIRE 17 -1 (-5800 4900)(-5800 4800);
WIRE 17 -1 (-5800 4800)(-5800 4700);
WIRE 17 -1 (-5800 4700)(-5800 4600);
WIRE 17 -1 (-5800 4500)(-5800 4600);
WIRE 17 -1 (-5800 4400)(-5800 4500);
WIRE 17 -1 (-5800 4300)(-5800 4400);
WIRE 17 -1 (-5800 4300)(-5800 4200);
WIRE 17 -1 (-5800 4200)(-5800 4100);
WIRE 17 -1 (-6000 3850)(-6000 3900);
WIRE 17 -1 (-6000 3800)(-6000 3850);
WIRE 17 -1 (-6000 3900)(-6500 3900);
FORCEPROP 2 LAST SIG_NAME M_D_CPU1_SA_CA<6:0>
J 0
(-6500 3910);
DISPLAY 0.489362 (-6500 3910);
WIRE 17 -1 (-6000 3450)(-6000 3500);
WIRE 17 -1 (-6000 3400)(-6000 3450);
WIRE 17 -1 (-6000 3500)(-6500 3500);
FORCEPROP 2 LAST SIG_NAME M_D_CPU1_SB_CA<6:0>
J 0
(-6500 3510);
DISPLAY 0.489362 (-6500 3510);
WIRE 17 -1 (-6000 3750)(-6000 3800);
WIRE 17 -1 (-6000 3350)(-6000 3400);
WIRE 17 -1 (-6000 3700)(-6000 3750);
WIRE 17 -1 (-6000 3650)(-6000 3700);
WIRE 17 -1 (-6000 3600)(-6000 3650);
WIRE 17 -1 (-6000 3300)(-6000 3350);
WIRE 17 -1 (-6000 3250)(-6000 3300);
WIRE 17 -1 (-6000 3200)(-6000 3250);
WIRE 17 -1 (-6000 6000)(-6600 6000);
WIRE 17 -1 (-6000 4950)(-6600 4950);
WIRE 16 -1 (-7450 2175)(-6725 2175);
FORCEPROP 2 LAST SIG_NAME M_D_CPU1_ALERT_N
J 0
(-7410 2185);
DISPLAY 0.489362 (-7410 2185);
WIRE 16 -1 (-6525 2175)(-5400 2175);
FORCEPROP 2 LAST SIG_NAME M_D_CPU1_ALERT_R_N
J 0
(-6235 2185);
DISPLAY 0.489362 (-6235 2185);
FORCEPROP 2 LASTPROP $XRERR UNIQUE?
J 0
(-6475 2185);
DISPLAY 0.638298 (-6475 2185);
PAINT MONO (-6475 2185);
DISPLAY INVISIBLE (-6475 2185);
WIRE 16 -1 (-6500 1225)(-5400 1225);
FORCEPROP 2 LAST SIG_NAME TP_M_D_CPU1_SA_TEST39D
J 0
(-6485 1235);
DISPLAY 0.489362 (-6485 1235);
FORCEPROP 2 LASTPROP $XRERR UNIQUE?
J 0
(-6740 1225);
DISPLAY 0.638298 (-6740 1225);
PAINT MONO (-6740 1225);
DISPLAY INVISIBLE (-6740 1225);
WIRE 16 -1 (-6500 3025)(-5400 3025);
FORCEPROP 2 LAST SIG_NAME M_D_CPU1_CLK_DP<0>
J 0
(-6500 3035);
DISPLAY 0.489362 (-6500 3035);
WIRE 16 -1 (-6500 2975)(-5400 2975);
FORCEPROP 2 LAST SIG_NAME M_D_CPU1_CLK_DN<0>
J 0
(-6500 2985);
DISPLAY 0.489362 (-6500 2985);
WIRE 16 -1 (-6500 2875)(-5400 2875);
FORCEPROP 2 LAST SIG_NAME M_D_CPU1_SA_CS_N<0>
J 0
(-6500 2885);
DISPLAY 0.489362 (-6500 2885);
WIRE 16 -1 (-6500 2825)(-5400 2825);
FORCEPROP 2 LAST SIG_NAME M_D_CPU1_SA_CS_N<1>
J 0
(-6500 2835);
DISPLAY 0.489362 (-6500 2835);
WIRE 16 -1 (-6500 2725)(-5400 2725);
FORCEPROP 2 LAST SIG_NAME M_D_CPU1_SA_RSP<0>
J 0
(-6500 2735);
DISPLAY 0.489362 (-6500 2735);
WIRE 16 -1 (-6500 2625)(-5400 2625);
FORCEPROP 2 LAST SIG_NAME M_D_CPU1_SA_PAR
J 0
(-6500 2635);
DISPLAY 0.489362 (-6500 2635);
WIRE 16 -1 (-6500 2525)(-5400 2525);
FORCEPROP 2 LAST SIG_NAME M_D_CPU1_SB_CS_N<0>
J 0
(-6500 2535);
DISPLAY 0.489362 (-6500 2535);
WIRE 16 -1 (-6500 2475)(-5400 2475);
FORCEPROP 2 LAST SIG_NAME M_D_CPU1_SB_CS_N<1>
J 0
(-6500 2485);
DISPLAY 0.489362 (-6500 2485);
WIRE 16 -1 (-6500 2375)(-5400 2375);
FORCEPROP 2 LAST SIG_NAME M_D_CPU1_SB_RSP<0>
J 0
(-6500 2385);
DISPLAY 0.489362 (-6500 2385);
WIRE 16 -1 (-6500 2275)(-5400 2275);
FORCEPROP 2 LAST SIG_NAME M_D_CPU1_SB_PAR
J 0
(-6500 2285);
DISPLAY 0.489362 (-6500 2285);
WIRE 16 -1 (-6500 2075)(-5400 2075);
FORCEPROP 2 LAST SIG_NAME M_D_CPU1_RESET_N
J 0
(-6500 2085);
DISPLAY 0.489362 (-6500 2085);
WIRE 16 -1 (-5700 4075)(-5400 4075);
WIRE 16 -1 (-5900 3325)(-5400 3325);
WIRE 16 -1 (-5900 3175)(-5400 3175);
WIRE 16 -1 (-5900 3575)(-5400 3575);
WIRE 16 -1 (-5900 3225)(-5400 3225);
WIRE 16 -1 (-5900 3625)(-5400 3625);
WIRE 16 -1 (-5900 3275)(-5400 3275);
WIRE 16 -1 (-5900 3675)(-5400 3675);
WIRE 16 -1 (-5900 4025)(-5400 4025);
WIRE 16 -1 (-5900 3725)(-5400 3725);
WIRE 16 -1 (-5900 3375)(-5400 3375);
WIRE 16 -1 (-5900 3775)(-5400 3775);
WIRE 16 -1 (-5900 3425)(-5400 3425);
WIRE 16 -1 (-5900 3825)(-5400 3825);
WIRE 16 -1 (-5900 3475)(-5400 3475);
WIRE 16 -1 (-5900 3875)(-5400 3875);
WIRE 16 -1 (-5700 4175)(-5400 4175);
WIRE 16 -1 (-5700 4275)(-5400 4275);
WIRE 16 -1 (-5700 4375)(-5400 4375);
WIRE 16 -1 (-5700 4475)(-5400 4475);
WIRE 16 -1 (-5700 4575)(-5400 4575);
WIRE 16 -1 (-5900 4125)(-5400 4125);
WIRE 16 -1 (-5700 4675)(-5400 4675);
WIRE 16 -1 (-5900 4225)(-5400 4225);
WIRE 16 -1 (-5700 4775)(-5400 4775);
WIRE 16 -1 (-5900 4325)(-5400 4325);
WIRE 16 -1 (-5700 4875)(-5400 4875);
WIRE 16 -1 (-5900 4425)(-5400 4425);
WIRE 16 -1 (-5700 4975)(-5400 4975);
WIRE 16 -1 (-5900 4525)(-5400 4525);
WIRE 16 -1 (-5900 5075)(-5400 5075);
WIRE 16 -1 (-5900 4625)(-5400 4625);
WIRE 16 -1 (-5900 4725)(-5400 4725);
WIRE 16 -1 (-5900 4825)(-5400 4825);
WIRE 16 -1 (-5900 4925)(-5400 4925);
WIRE 16 -1 (-5700 6025)(-5400 6025);
WIRE 16 -1 (-5900 5575)(-5400 5575);
WIRE 16 -1 (-5900 5675)(-5400 5675);
WIRE 16 -1 (-5900 5775)(-5400 5775);
WIRE 16 -1 (-5900 5875)(-5400 5875);
WIRE 16 -1 (-5900 5975)(-5400 5975);
WIRE 16 -1 (-5700 5125)(-5400 5125);
WIRE 16 -1 (-5700 5225)(-5400 5225);
WIRE 16 -1 (-5700 5325)(-5400 5325);
WIRE 16 -1 (-5700 5425)(-5400 5425);
WIRE 16 -1 (-5700 5525)(-5400 5525);
WIRE 16 -1 (-5700 5625)(-5400 5625);
WIRE 16 -1 (-5900 5175)(-5400 5175);
WIRE 16 -1 (-5700 5725)(-5400 5725);
WIRE 16 -1 (-5900 5275)(-5400 5275);
WIRE 16 -1 (-5700 5825)(-5400 5825);
WIRE 16 -1 (-5900 5375)(-5400 5375);
WIRE 16 -1 (-5700 5925)(-5400 5925);
WIRE 16 -1 (-5900 5475)(-5400 5475);
WIRE 16 -1 (-3800 1875)(-3375 1875);
WIRE 16 -1 (-3800 1925)(-3375 1925);
WIRE 16 -1 (-3800 1975)(-3375 1975);
WIRE 16 -1 (-3800 1625)(-3375 1625);
WIRE 16 -1 (-3800 1675)(-3375 1675);
WIRE 16 -1 (-3800 1725)(-3375 1725);
WIRE 16 -1 (-3800 1775)(-3375 1775);
WIRE 16 -1 (-3800 1825)(-3375 1825);
WIRE 16 -1 (-3800 3025)(-3375 3025);
WIRE 16 -1 (-3800 2075)(-3375 2075);
WIRE 16 -1 (-3800 2125)(-3375 2125);
WIRE 16 -1 (-3800 2525)(-3375 2525);
WIRE 16 -1 (-3800 2175)(-3375 2175);
WIRE 16 -1 (-3800 2575)(-3375 2575);
WIRE 16 -1 (-3800 2225)(-3375 2225);
WIRE 16 -1 (-3800 2275)(-3375 2275);
WIRE 16 -1 (-3800 2325)(-3375 2325);
WIRE 16 -1 (-3800 2375)(-3375 2375);
WIRE 16 -1 (-3800 2425)(-3375 2425);
WIRE 16 -1 (-3800 2625)(-3375 2625);
WIRE 16 -1 (-3800 2675)(-3375 2675);
WIRE 16 -1 (-3800 2725)(-3375 2725);
WIRE 16 -1 (-3800 2775)(-3375 2775);
WIRE 16 -1 (-3800 2825)(-3375 2825);
WIRE 16 -1 (-3800 2875)(-3375 2875);
WIRE 16 -1 (-3800 2975)(-3375 2975);
WIRE 16 -1 (-3800 3625)(-3375 3625);
WIRE 16 -1 (-3800 3675)(-3375 3675);
WIRE 16 -1 (-3800 3075)(-3375 3075);
WIRE 16 -1 (-3800 3125)(-3375 3125);
WIRE 16 -1 (-3800 3725)(-3375 3725);
WIRE 16 -1 (-3800 3175)(-3375 3175);
WIRE 16 -1 (-3800 3775)(-3375 3775);
WIRE 16 -1 (-3800 3225)(-3375 3225);
WIRE 16 -1 (-3800 3875)(-3375 3875);
WIRE 16 -1 (-3800 3275)(-3375 3275);
WIRE 16 -1 (-3800 3925)(-3375 3925);
WIRE 16 -1 (-3800 3325)(-3375 3325);
WIRE 16 -1 (-3800 3975)(-3375 3975);
WIRE 16 -1 (-3800 3425)(-3375 3425);
WIRE 16 -1 (-3800 4025)(-3375 4025);
WIRE 16 -1 (-3800 3475)(-3375 3475);
WIRE 16 -1 (-3800 4075)(-3375 4075);
WIRE 16 -1 (-3800 3525)(-3375 3525);
WIRE 16 -1 (-3800 3575)(-3375 3575);
WIRE 16 -1 (-3800 5075)(-3375 5075);
WIRE 16 -1 (-3800 4475)(-3375 4475);
WIRE 16 -1 (-3800 4175)(-3375 4175);
WIRE 16 -1 (-3800 4525)(-3375 4525);
WIRE 16 -1 (-3800 4225)(-3375 4225);
WIRE 16 -1 (-3800 4575)(-3375 4575);
WIRE 16 -1 (-3800 4625)(-3375 4625);
WIRE 16 -1 (-3800 4675)(-3375 4675);
WIRE 16 -1 (-3800 4775)(-3375 4775);
WIRE 16 -1 (-3800 4825)(-3375 4825);
WIRE 16 -1 (-3800 4875)(-3375 4875);
WIRE 16 -1 (-3800 4925)(-3375 4925);
WIRE 16 -1 (-3800 4325)(-3375 4325);
WIRE 16 -1 (-3800 4375)(-3375 4375);
WIRE 16 -1 (-3800 4975)(-3375 4975);
WIRE 16 -1 (-3800 5025)(-3375 5025);
WIRE 16 -1 (-3800 4425)(-3375 4425);
WIRE 16 -1 (-3800 4125)(-3375 4125);
WIRE 16 -1 (-3800 5925)(-3375 5925);
WIRE 16 -1 (-3800 5975)(-3375 5975);
WIRE 16 -1 (-3800 5125)(-3375 5125);
WIRE 16 -1 (-3800 6025)(-3375 6025);
WIRE 16 -1 (-3800 5225)(-3375 5225);
WIRE 16 -1 (-3800 5275)(-3375 5275);
WIRE 16 -1 (-3800 5325)(-3375 5325);
WIRE 16 -1 (-3800 5375)(-3375 5375);
WIRE 16 -1 (-3800 5425)(-3375 5425);
WIRE 16 -1 (-3800 5475)(-3375 5475);
WIRE 16 -1 (-3800 5525)(-3375 5525);
WIRE 16 -1 (-3800 5575)(-3375 5575);
WIRE 16 -1 (-3800 5675)(-3375 5675);
WIRE 16 -1 (-3800 5725)(-3375 5725);
WIRE 16 -1 (-3800 5775)(-3375 5775);
WIRE 16 -1 (-3800 5825)(-3375 5825);
WIRE 16 -1 (-3800 5875)(-3375 5875);
QUIT
